FILE_TYPE = MACRO_DRAWING;
SET COLOR_WIRE YELLOW;
SET COLOR_PROP MONO;
SET COLOR_DOT WHITE;
SET COLOR_ARC YELLOW;
SET COLOR_BODY GREEN;
SET COLOR_NOTE MONO;
SET PROP_DISPLAY VALUE;
SET PAGE_NUMBER P57;
FORCEADD OFFPAGE..5
(-6425 525);
FORCEPROP 2 LAST $XR1 78 
J 0
(-6769 525);
DISPLAY 0.638298 (-6769 525);
PAINT MONO (-6769 525);
FORCEPROP 2 LAST $XR0 77 
J 0
(-6679 525);
DISPLAY 0.638298 (-6679 525);
PAINT MONO (-6679 525);
FORCEPROP 2 LAST CDS_LIB mstr_standard
J 0
(-6425 525);
PAINT MONO (-6425 525);
DISPLAY INVISIBLE (-6425 525);
FORCEPROP 1 LAST OFFPAGE TRUE
J 0
(-6100 400);
DISPLAY 1.170213 (-6100 400);
PAINT GREEN (-6100 400);
DISPLAY INVISIBLE (-6100 400);
FORCEPROP 1 LAST COMMENT_BODY TRUE
J 0
(-6325 450);
DISPLAY 1.170213 (-6325 450);
PAINT GREEN (-6325 450);
DISPLAY INVISIBLE (-6325 450);
FORCEPROP 2 LAST PATH I1
J 0
(-6375 600);
DISPLAY 1.021277 (-6375 600);
PAINT ORANGE (-6375 600);
DISPLAY INVISIBLE (-6375 600);
FORCEADD TAP..6
(-5575 825);
FORCEPROP 3 LASTPIN (-5525 825) SIG_NAME M_G_CLK_DP<0>
J 0
(-5515 835);
DISPLAY 0.659574 (-5515 835);
PAINT MONO (-5515 835);
DISPLAY INVISIBLE (-5515 835);
FORCEPROP 1 LASTPIN (-5525 825) BN 0
J 0
(-5577 833);
DISPLAY 0.617021 (-5577 833);
PAINT GREEN (-5577 833);
FORCEPROP 2 LAST CDS_LIB mstr_standard
J 0
(-5575 825);
PAINT MONO (-5575 825);
DISPLAY INVISIBLE (-5575 825);
FORCEPROP 1 LAST BODY_TYPE PLUMBING
J 0
(-5575 775);
DISPLAY 1.595745 (-5575 775);
PAINT GREEN (-5575 775);
DISPLAY INVISIBLE (-5575 775);
FORCEPROP 1 LAST HDL_TAP TRUE
J 0
(-5250 700);
DISPLAY 1.595745 (-5250 700);
PAINT GREEN (-5250 700);
DISPLAY INVISIBLE (-5250 700);
FORCEPROP 1 LAST PATH I10
J 0
(-5577 825);
DISPLAY 0.872340 (-5577 825);
PAINT GREEN (-5577 825);
DISPLAY INVISIBLE (-5577 825);
FORCEADD TAP..6
R 2
(-2850 1575);
FORCEPROP 3 LASTPIN (-2900 1575) SIG_NAME M_G_ODT<3>
J 0
(-2890 1585);
DISPLAY 0.659574 (-2890 1585);
PAINT MONO (-2890 1585);
DISPLAY INVISIBLE (-2890 1585);
FORCEPROP 1 LASTPIN (-2900 1575) BN 3
J 2
(-2848 1583);
DISPLAY 0.617021 (-2848 1583);
PAINT GREEN (-2848 1583);
FORCEPROP 2 LAST CDS_LIB mstr_standard
J 0
(-2850 1575);
PAINT MONO (-2850 1575);
DISPLAY INVISIBLE (-2850 1575);
FORCEPROP 1 LAST BODY_TYPE PLUMBING
J 2
(-2850 1525);
DISPLAY 1.595745 (-2850 1525);
PAINT GREEN (-2850 1525);
DISPLAY INVISIBLE (-2850 1525);
FORCEPROP 1 LAST HDL_TAP TRUE
J 2
(-3175 1450);
DISPLAY 1.595745 (-3175 1450);
PAINT GREEN (-3175 1450);
DISPLAY INVISIBLE (-3175 1450);
FORCEPROP 1 LAST PATH I100
J 2
(-2848 1575);
DISPLAY 0.872340 (-2848 1575);
PAINT GREEN (-2848 1575);
DISPLAY INVISIBLE (-2848 1575);
FORCEADD TAP..6
R 2
(-2850 1525);
FORCEPROP 3 LASTPIN (-2900 1525) SIG_NAME M_G_ODT<2>
J 0
(-2890 1535);
DISPLAY 0.659574 (-2890 1535);
PAINT MONO (-2890 1535);
DISPLAY INVISIBLE (-2890 1535);
FORCEPROP 1 LASTPIN (-2900 1525) BN 2
J 2
(-2848 1533);
DISPLAY 0.617021 (-2848 1533);
PAINT GREEN (-2848 1533);
FORCEPROP 2 LAST CDS_LIB mstr_standard
J 0
(-2850 1525);
PAINT MONO (-2850 1525);
DISPLAY INVISIBLE (-2850 1525);
FORCEPROP 1 LAST BODY_TYPE PLUMBING
J 2
(-2850 1475);
DISPLAY 1.595745 (-2850 1475);
PAINT GREEN (-2850 1475);
DISPLAY INVISIBLE (-2850 1475);
FORCEPROP 1 LAST HDL_TAP TRUE
J 2
(-3175 1400);
DISPLAY 1.595745 (-3175 1400);
PAINT GREEN (-3175 1400);
DISPLAY INVISIBLE (-3175 1400);
FORCEPROP 1 LAST PATH I101
J 2
(-2848 1525);
DISPLAY 0.872340 (-2848 1525);
PAINT GREEN (-2848 1525);
DISPLAY INVISIBLE (-2848 1525);
FORCEADD TAP..6
R 2
(-2850 1475);
FORCEPROP 3 LASTPIN (-2900 1475) SIG_NAME M_G_ODT<1>
J 0
(-2890 1485);
DISPLAY 0.659574 (-2890 1485);
PAINT MONO (-2890 1485);
DISPLAY INVISIBLE (-2890 1485);
FORCEPROP 1 LASTPIN (-2900 1475) BN 1
J 2
(-2848 1483);
DISPLAY 0.617021 (-2848 1483);
PAINT GREEN (-2848 1483);
FORCEPROP 2 LAST CDS_LIB mstr_standard
J 0
(-2850 1475);
PAINT MONO (-2850 1475);
DISPLAY INVISIBLE (-2850 1475);
FORCEPROP 1 LAST BODY_TYPE PLUMBING
J 2
(-2850 1425);
DISPLAY 1.595745 (-2850 1425);
PAINT GREEN (-2850 1425);
DISPLAY INVISIBLE (-2850 1425);
FORCEPROP 1 LAST HDL_TAP TRUE
J 2
(-3175 1350);
DISPLAY 1.595745 (-3175 1350);
PAINT GREEN (-3175 1350);
DISPLAY INVISIBLE (-3175 1350);
FORCEPROP 1 LAST PATH I102
J 2
(-2848 1475);
DISPLAY 0.872340 (-2848 1475);
PAINT GREEN (-2848 1475);
DISPLAY INVISIBLE (-2848 1475);
FORCEADD TAP..6
R 2
(-2850 1675);
FORCEPROP 3 LASTPIN (-2900 1675) SIG_NAME M_G_CKE<0>
J 0
(-2890 1685);
DISPLAY 0.659574 (-2890 1685);
PAINT MONO (-2890 1685);
DISPLAY INVISIBLE (-2890 1685);
FORCEPROP 1 LASTPIN (-2900 1675) BN 0
J 2
(-2848 1683);
DISPLAY 0.617021 (-2848 1683);
PAINT GREEN (-2848 1683);
FORCEPROP 2 LAST CDS_LIB mstr_standard
J 0
(-2850 1675);
PAINT MONO (-2850 1675);
DISPLAY INVISIBLE (-2850 1675);
FORCEPROP 1 LAST BODY_TYPE PLUMBING
J 2
(-2850 1625);
DISPLAY 1.595745 (-2850 1625);
PAINT GREEN (-2850 1625);
DISPLAY INVISIBLE (-2850 1625);
FORCEPROP 1 LAST HDL_TAP TRUE
J 2
(-3175 1550);
DISPLAY 1.595745 (-3175 1550);
PAINT GREEN (-3175 1550);
DISPLAY INVISIBLE (-3175 1550);
FORCEPROP 1 LAST PATH I103
J 2
(-2848 1675);
DISPLAY 0.872340 (-2848 1675);
PAINT GREEN (-2848 1675);
DISPLAY INVISIBLE (-2848 1675);
FORCEADD TAP..6
R 2
(-2850 1725);
FORCEPROP 3 LASTPIN (-2900 1725) SIG_NAME M_G_CKE<1>
J 0
(-2890 1735);
DISPLAY 0.659574 (-2890 1735);
PAINT MONO (-2890 1735);
DISPLAY INVISIBLE (-2890 1735);
FORCEPROP 1 LASTPIN (-2900 1725) BN 1
J 2
(-2848 1733);
DISPLAY 0.617021 (-2848 1733);
PAINT GREEN (-2848 1733);
FORCEPROP 2 LAST CDS_LIB mstr_standard
J 0
(-2850 1725);
PAINT MONO (-2850 1725);
DISPLAY INVISIBLE (-2850 1725);
FORCEPROP 1 LAST BODY_TYPE PLUMBING
J 2
(-2850 1675);
DISPLAY 1.595745 (-2850 1675);
PAINT GREEN (-2850 1675);
DISPLAY INVISIBLE (-2850 1675);
FORCEPROP 1 LAST HDL_TAP TRUE
J 2
(-3175 1600);
DISPLAY 1.595745 (-3175 1600);
PAINT GREEN (-3175 1600);
DISPLAY INVISIBLE (-3175 1600);
FORCEPROP 1 LAST PATH I104
J 2
(-2848 1725);
DISPLAY 0.872340 (-2848 1725);
PAINT GREEN (-2848 1725);
DISPLAY INVISIBLE (-2848 1725);
FORCEADD TAP..6
R 2
(-2850 1775);
FORCEPROP 3 LASTPIN (-2900 1775) SIG_NAME M_G_CKE<2>
J 0
(-2890 1785);
DISPLAY 0.659574 (-2890 1785);
PAINT MONO (-2890 1785);
DISPLAY INVISIBLE (-2890 1785);
FORCEPROP 1 LASTPIN (-2900 1775) BN 2
J 2
(-2848 1783);
DISPLAY 0.617021 (-2848 1783);
PAINT GREEN (-2848 1783);
FORCEPROP 2 LAST CDS_LIB mstr_standard
J 0
(-2850 1775);
PAINT MONO (-2850 1775);
DISPLAY INVISIBLE (-2850 1775);
FORCEPROP 1 LAST BODY_TYPE PLUMBING
J 2
(-2850 1725);
DISPLAY 1.595745 (-2850 1725);
PAINT GREEN (-2850 1725);
DISPLAY INVISIBLE (-2850 1725);
FORCEPROP 1 LAST HDL_TAP TRUE
J 2
(-3175 1650);
DISPLAY 1.595745 (-3175 1650);
PAINT GREEN (-3175 1650);
DISPLAY INVISIBLE (-3175 1650);
FORCEPROP 1 LAST PATH I105
J 2
(-2848 1775);
DISPLAY 0.872340 (-2848 1775);
PAINT GREEN (-2848 1775);
DISPLAY INVISIBLE (-2848 1775);
FORCEADD TAP..6
R 2
(-2850 1825);
FORCEPROP 3 LASTPIN (-2900 1825) SIG_NAME M_G_CKE<3>
J 0
(-2890 1835);
DISPLAY 0.659574 (-2890 1835);
PAINT MONO (-2890 1835);
DISPLAY INVISIBLE (-2890 1835);
FORCEPROP 1 LASTPIN (-2900 1825) BN 3
J 2
(-2848 1833);
DISPLAY 0.617021 (-2848 1833);
PAINT GREEN (-2848 1833);
FORCEPROP 2 LAST CDS_LIB mstr_standard
J 0
(-2850 1825);
PAINT MONO (-2850 1825);
DISPLAY INVISIBLE (-2850 1825);
FORCEPROP 1 LAST BODY_TYPE PLUMBING
J 2
(-2850 1775);
DISPLAY 1.595745 (-2850 1775);
PAINT GREEN (-2850 1775);
DISPLAY INVISIBLE (-2850 1775);
FORCEPROP 1 LAST HDL_TAP TRUE
J 2
(-3175 1700);
DISPLAY 1.595745 (-3175 1700);
PAINT GREEN (-3175 1700);
DISPLAY INVISIBLE (-3175 1700);
FORCEPROP 1 LAST PATH I106
J 2
(-2848 1825);
DISPLAY 0.872340 (-2848 1825);
PAINT GREEN (-2848 1825);
DISPLAY INVISIBLE (-2848 1825);
FORCEADD TAP..6
R 2
(-2850 1925);
FORCEPROP 3 LASTPIN (-2900 1925) SIG_NAME M_G_MA<0>
J 0
(-2890 1935);
DISPLAY 0.659574 (-2890 1935);
PAINT MONO (-2890 1935);
DISPLAY INVISIBLE (-2890 1935);
FORCEPROP 1 LASTPIN (-2900 1925) BN 0
J 2
(-2848 1933);
DISPLAY 0.617021 (-2848 1933);
PAINT GREEN (-2848 1933);
FORCEPROP 2 LAST CDS_LIB mstr_standard
J 0
(-2850 1925);
PAINT MONO (-2850 1925);
DISPLAY INVISIBLE (-2850 1925);
FORCEPROP 1 LAST BODY_TYPE PLUMBING
J 2
(-2850 1875);
DISPLAY 1.595745 (-2850 1875);
PAINT GREEN (-2850 1875);
DISPLAY INVISIBLE (-2850 1875);
FORCEPROP 1 LAST HDL_TAP TRUE
J 2
(-3175 1800);
DISPLAY 1.595745 (-3175 1800);
PAINT GREEN (-3175 1800);
DISPLAY INVISIBLE (-3175 1800);
FORCEPROP 1 LAST PATH I107
J 2
(-2848 1925);
DISPLAY 0.872340 (-2848 1925);
PAINT GREEN (-2848 1925);
DISPLAY INVISIBLE (-2848 1925);
FORCEADD TAP..6
R 2
(-2850 1975);
FORCEPROP 3 LASTPIN (-2900 1975) SIG_NAME M_G_MA<1>
J 0
(-2890 1985);
DISPLAY 0.659574 (-2890 1985);
PAINT MONO (-2890 1985);
DISPLAY INVISIBLE (-2890 1985);
FORCEPROP 1 LASTPIN (-2900 1975) BN 1
J 2
(-2848 1983);
DISPLAY 0.617021 (-2848 1983);
PAINT GREEN (-2848 1983);
FORCEPROP 2 LAST CDS_LIB mstr_standard
J 0
(-2850 1975);
PAINT MONO (-2850 1975);
DISPLAY INVISIBLE (-2850 1975);
FORCEPROP 1 LAST BODY_TYPE PLUMBING
J 2
(-2850 1925);
DISPLAY 1.595745 (-2850 1925);
PAINT GREEN (-2850 1925);
DISPLAY INVISIBLE (-2850 1925);
FORCEPROP 1 LAST HDL_TAP TRUE
J 2
(-3175 1850);
DISPLAY 1.595745 (-3175 1850);
PAINT GREEN (-3175 1850);
DISPLAY INVISIBLE (-3175 1850);
FORCEPROP 1 LAST PATH I108
J 2
(-2848 1975);
DISPLAY 0.872340 (-2848 1975);
PAINT GREEN (-2848 1975);
DISPLAY INVISIBLE (-2848 1975);
FORCEADD TAP..6
R 2
(-2850 2075);
FORCEPROP 3 LASTPIN (-2900 2075) SIG_NAME M_G_MA<3>
J 0
(-2890 2085);
DISPLAY 0.659574 (-2890 2085);
PAINT MONO (-2890 2085);
DISPLAY INVISIBLE (-2890 2085);
FORCEPROP 1 LASTPIN (-2900 2075) BN 3
J 2
(-2848 2083);
DISPLAY 0.617021 (-2848 2083);
PAINT GREEN (-2848 2083);
FORCEPROP 2 LAST CDS_LIB mstr_standard
J 0
(-2850 2075);
PAINT MONO (-2850 2075);
DISPLAY INVISIBLE (-2850 2075);
FORCEPROP 1 LAST BODY_TYPE PLUMBING
J 2
(-2850 2025);
DISPLAY 1.595745 (-2850 2025);
PAINT GREEN (-2850 2025);
DISPLAY INVISIBLE (-2850 2025);
FORCEPROP 1 LAST HDL_TAP TRUE
J 2
(-3175 1950);
DISPLAY 1.595745 (-3175 1950);
PAINT GREEN (-3175 1950);
DISPLAY INVISIBLE (-3175 1950);
FORCEPROP 1 LAST PATH I109
J 2
(-2848 2075);
DISPLAY 0.872340 (-2848 2075);
PAINT GREEN (-2848 2075);
DISPLAY INVISIBLE (-2848 2075);
FORCEADD TAP..6
(-5575 925);
FORCEPROP 3 LASTPIN (-5525 925) SIG_NAME M_G_CLK_DP<2>
J 0
(-5515 935);
DISPLAY 0.659574 (-5515 935);
PAINT MONO (-5515 935);
DISPLAY INVISIBLE (-5515 935);
FORCEPROP 1 LASTPIN (-5525 925) BN 2
J 0
(-5577 933);
DISPLAY 0.617021 (-5577 933);
PAINT GREEN (-5577 933);
FORCEPROP 2 LAST CDS_LIB mstr_standard
J 0
(-5575 925);
PAINT MONO (-5575 925);
DISPLAY INVISIBLE (-5575 925);
FORCEPROP 1 LAST BODY_TYPE PLUMBING
J 0
(-5575 875);
DISPLAY 1.595745 (-5575 875);
PAINT GREEN (-5575 875);
DISPLAY INVISIBLE (-5575 875);
FORCEPROP 1 LAST HDL_TAP TRUE
J 0
(-5250 800);
DISPLAY 1.595745 (-5250 800);
PAINT GREEN (-5250 800);
DISPLAY INVISIBLE (-5250 800);
FORCEPROP 1 LAST PATH I11
J 0
(-5577 925);
DISPLAY 0.872340 (-5577 925);
PAINT GREEN (-5577 925);
DISPLAY INVISIBLE (-5577 925);
FORCEADD TAP..6
R 2
(-2850 2025);
FORCEPROP 3 LASTPIN (-2900 2025) SIG_NAME M_G_MA<2>
J 0
(-2890 2035);
DISPLAY 0.659574 (-2890 2035);
PAINT MONO (-2890 2035);
DISPLAY INVISIBLE (-2890 2035);
FORCEPROP 1 LASTPIN (-2900 2025) BN 2
J 2
(-2848 2033);
DISPLAY 0.617021 (-2848 2033);
PAINT GREEN (-2848 2033);
FORCEPROP 2 LAST CDS_LIB mstr_standard
J 0
(-2850 2025);
PAINT MONO (-2850 2025);
DISPLAY INVISIBLE (-2850 2025);
FORCEPROP 1 LAST BODY_TYPE PLUMBING
J 2
(-2850 1975);
DISPLAY 1.595745 (-2850 1975);
PAINT GREEN (-2850 1975);
DISPLAY INVISIBLE (-2850 1975);
FORCEPROP 1 LAST HDL_TAP TRUE
J 2
(-3175 1900);
DISPLAY 1.595745 (-3175 1900);
PAINT GREEN (-3175 1900);
DISPLAY INVISIBLE (-3175 1900);
FORCEPROP 1 LAST PATH I110
J 2
(-2848 2025);
DISPLAY 0.872340 (-2848 2025);
PAINT GREEN (-2848 2025);
DISPLAY INVISIBLE (-2848 2025);
FORCEADD TAP..6
R 2
(-2850 2125);
FORCEPROP 3 LASTPIN (-2900 2125) SIG_NAME M_G_MA<4>
J 0
(-2890 2135);
DISPLAY 0.659574 (-2890 2135);
PAINT MONO (-2890 2135);
DISPLAY INVISIBLE (-2890 2135);
FORCEPROP 1 LASTPIN (-2900 2125) BN 4
J 2
(-2848 2133);
DISPLAY 0.617021 (-2848 2133);
PAINT GREEN (-2848 2133);
FORCEPROP 2 LAST CDS_LIB mstr_standard
J 0
(-2850 2125);
PAINT MONO (-2850 2125);
DISPLAY INVISIBLE (-2850 2125);
FORCEPROP 1 LAST BODY_TYPE PLUMBING
J 2
(-2850 2075);
DISPLAY 1.595745 (-2850 2075);
PAINT GREEN (-2850 2075);
DISPLAY INVISIBLE (-2850 2075);
FORCEPROP 1 LAST HDL_TAP TRUE
J 2
(-3175 2000);
DISPLAY 1.595745 (-3175 2000);
PAINT GREEN (-3175 2000);
DISPLAY INVISIBLE (-3175 2000);
FORCEPROP 1 LAST PATH I111
J 2
(-2848 2125);
DISPLAY 0.872340 (-2848 2125);
PAINT GREEN (-2848 2125);
DISPLAY INVISIBLE (-2848 2125);
FORCEADD TAP..6
R 2
(-2850 2175);
FORCEPROP 3 LASTPIN (-2900 2175) SIG_NAME M_G_MA<5>
J 0
(-2890 2185);
DISPLAY 0.659574 (-2890 2185);
PAINT MONO (-2890 2185);
DISPLAY INVISIBLE (-2890 2185);
FORCEPROP 1 LASTPIN (-2900 2175) BN 5
J 2
(-2848 2183);
DISPLAY 0.617021 (-2848 2183);
PAINT GREEN (-2848 2183);
FORCEPROP 2 LAST CDS_LIB mstr_standard
J 0
(-2850 2175);
PAINT MONO (-2850 2175);
DISPLAY INVISIBLE (-2850 2175);
FORCEPROP 1 LAST BODY_TYPE PLUMBING
J 2
(-2850 2125);
DISPLAY 1.595745 (-2850 2125);
PAINT GREEN (-2850 2125);
DISPLAY INVISIBLE (-2850 2125);
FORCEPROP 1 LAST HDL_TAP TRUE
J 2
(-3175 2050);
DISPLAY 1.595745 (-3175 2050);
PAINT GREEN (-3175 2050);
DISPLAY INVISIBLE (-3175 2050);
FORCEPROP 1 LAST PATH I112
J 2
(-2848 2175);
DISPLAY 0.872340 (-2848 2175);
PAINT GREEN (-2848 2175);
DISPLAY INVISIBLE (-2848 2175);
FORCEADD TAP..6
R 2
(-2850 2225);
FORCEPROP 3 LASTPIN (-2900 2225) SIG_NAME M_G_MA<6>
J 0
(-2890 2235);
DISPLAY 0.659574 (-2890 2235);
PAINT MONO (-2890 2235);
DISPLAY INVISIBLE (-2890 2235);
FORCEPROP 1 LASTPIN (-2900 2225) BN 6
J 2
(-2848 2233);
DISPLAY 0.617021 (-2848 2233);
PAINT GREEN (-2848 2233);
FORCEPROP 2 LAST CDS_LIB mstr_standard
J 0
(-2850 2225);
PAINT MONO (-2850 2225);
DISPLAY INVISIBLE (-2850 2225);
FORCEPROP 1 LAST BODY_TYPE PLUMBING
J 2
(-2850 2175);
DISPLAY 1.595745 (-2850 2175);
PAINT GREEN (-2850 2175);
DISPLAY INVISIBLE (-2850 2175);
FORCEPROP 1 LAST HDL_TAP TRUE
J 2
(-3175 2100);
DISPLAY 1.595745 (-3175 2100);
PAINT GREEN (-3175 2100);
DISPLAY INVISIBLE (-3175 2100);
FORCEPROP 1 LAST PATH I113
J 2
(-2848 2225);
DISPLAY 0.872340 (-2848 2225);
PAINT GREEN (-2848 2225);
DISPLAY INVISIBLE (-2848 2225);
FORCEADD TAP..6
R 2
(-2850 2325);
FORCEPROP 3 LASTPIN (-2900 2325) SIG_NAME M_G_MA<8>
J 0
(-2890 2335);
DISPLAY 0.659574 (-2890 2335);
PAINT MONO (-2890 2335);
DISPLAY INVISIBLE (-2890 2335);
FORCEPROP 1 LASTPIN (-2900 2325) BN 8
J 2
(-2848 2333);
DISPLAY 0.617021 (-2848 2333);
PAINT GREEN (-2848 2333);
FORCEPROP 2 LAST CDS_LIB mstr_standard
J 0
(-2850 2325);
PAINT MONO (-2850 2325);
DISPLAY INVISIBLE (-2850 2325);
FORCEPROP 1 LAST BODY_TYPE PLUMBING
J 2
(-2850 2275);
DISPLAY 1.595745 (-2850 2275);
PAINT GREEN (-2850 2275);
DISPLAY INVISIBLE (-2850 2275);
FORCEPROP 1 LAST HDL_TAP TRUE
J 2
(-3175 2200);
DISPLAY 1.595745 (-3175 2200);
PAINT GREEN (-3175 2200);
DISPLAY INVISIBLE (-3175 2200);
FORCEPROP 1 LAST PATH I114
J 2
(-2848 2325);
DISPLAY 0.872340 (-2848 2325);
PAINT GREEN (-2848 2325);
DISPLAY INVISIBLE (-2848 2325);
FORCEADD TAP..6
R 2
(-2850 2275);
FORCEPROP 3 LASTPIN (-2900 2275) SIG_NAME M_G_MA<7>
J 0
(-2890 2285);
DISPLAY 0.659574 (-2890 2285);
PAINT MONO (-2890 2285);
DISPLAY INVISIBLE (-2890 2285);
FORCEPROP 1 LASTPIN (-2900 2275) BN 7
J 2
(-2848 2283);
DISPLAY 0.617021 (-2848 2283);
PAINT GREEN (-2848 2283);
FORCEPROP 2 LAST CDS_LIB mstr_standard
J 0
(-2850 2275);
PAINT MONO (-2850 2275);
DISPLAY INVISIBLE (-2850 2275);
FORCEPROP 1 LAST BODY_TYPE PLUMBING
J 2
(-2850 2225);
DISPLAY 1.595745 (-2850 2225);
PAINT GREEN (-2850 2225);
DISPLAY INVISIBLE (-2850 2225);
FORCEPROP 1 LAST HDL_TAP TRUE
J 2
(-3175 2150);
DISPLAY 1.595745 (-3175 2150);
PAINT GREEN (-3175 2150);
DISPLAY INVISIBLE (-3175 2150);
FORCEPROP 1 LAST PATH I115
J 2
(-2848 2275);
DISPLAY 0.872340 (-2848 2275);
PAINT GREEN (-2848 2275);
DISPLAY INVISIBLE (-2848 2275);
FORCEADD TAP..6
R 2
(-2850 2475);
FORCEPROP 3 LASTPIN (-2900 2475) SIG_NAME M_G_MA<11>
J 0
(-2890 2485);
DISPLAY 0.659574 (-2890 2485);
PAINT MONO (-2890 2485);
DISPLAY INVISIBLE (-2890 2485);
FORCEPROP 1 LASTPIN (-2900 2475) BN 11
J 2
(-2848 2483);
DISPLAY 0.617021 (-2848 2483);
PAINT GREEN (-2848 2483);
FORCEPROP 2 LAST CDS_LIB mstr_standard
J 0
(-2850 2475);
PAINT MONO (-2850 2475);
DISPLAY INVISIBLE (-2850 2475);
FORCEPROP 1 LAST BODY_TYPE PLUMBING
J 2
(-2850 2425);
DISPLAY 1.595745 (-2850 2425);
PAINT GREEN (-2850 2425);
DISPLAY INVISIBLE (-2850 2425);
FORCEPROP 1 LAST HDL_TAP TRUE
J 2
(-3175 2350);
DISPLAY 1.595745 (-3175 2350);
PAINT GREEN (-3175 2350);
DISPLAY INVISIBLE (-3175 2350);
FORCEPROP 1 LAST PATH I116
J 2
(-2848 2475);
DISPLAY 0.872340 (-2848 2475);
PAINT GREEN (-2848 2475);
DISPLAY INVISIBLE (-2848 2475);
FORCEADD TAP..6
R 2
(-2850 2425);
FORCEPROP 3 LASTPIN (-2900 2425) SIG_NAME M_G_MA<10>
J 0
(-2890 2435);
DISPLAY 0.659574 (-2890 2435);
PAINT MONO (-2890 2435);
DISPLAY INVISIBLE (-2890 2435);
FORCEPROP 1 LASTPIN (-2900 2425) BN 10
J 2
(-2848 2433);
DISPLAY 0.617021 (-2848 2433);
PAINT GREEN (-2848 2433);
FORCEPROP 2 LAST CDS_LIB mstr_standard
J 0
(-2850 2425);
PAINT MONO (-2850 2425);
DISPLAY INVISIBLE (-2850 2425);
FORCEPROP 1 LAST BODY_TYPE PLUMBING
J 2
(-2850 2375);
DISPLAY 1.595745 (-2850 2375);
PAINT GREEN (-2850 2375);
DISPLAY INVISIBLE (-2850 2375);
FORCEPROP 1 LAST HDL_TAP TRUE
J 2
(-3175 2300);
DISPLAY 1.595745 (-3175 2300);
PAINT GREEN (-3175 2300);
DISPLAY INVISIBLE (-3175 2300);
FORCEPROP 1 LAST PATH I117
J 2
(-2848 2425);
DISPLAY 0.872340 (-2848 2425);
PAINT GREEN (-2848 2425);
DISPLAY INVISIBLE (-2848 2425);
FORCEADD TAP..6
R 2
(-2850 2375);
FORCEPROP 3 LASTPIN (-2900 2375) SIG_NAME M_G_MA<9>
J 0
(-2890 2385);
DISPLAY 0.659574 (-2890 2385);
PAINT MONO (-2890 2385);
DISPLAY INVISIBLE (-2890 2385);
FORCEPROP 1 LASTPIN (-2900 2375) BN 9
J 2
(-2848 2383);
DISPLAY 0.617021 (-2848 2383);
PAINT GREEN (-2848 2383);
FORCEPROP 2 LAST CDS_LIB mstr_standard
J 0
(-2850 2375);
PAINT MONO (-2850 2375);
DISPLAY INVISIBLE (-2850 2375);
FORCEPROP 1 LAST BODY_TYPE PLUMBING
J 2
(-2850 2325);
DISPLAY 1.595745 (-2850 2325);
PAINT GREEN (-2850 2325);
DISPLAY INVISIBLE (-2850 2325);
FORCEPROP 1 LAST HDL_TAP TRUE
J 2
(-3175 2250);
DISPLAY 1.595745 (-3175 2250);
PAINT GREEN (-3175 2250);
DISPLAY INVISIBLE (-3175 2250);
FORCEPROP 1 LAST PATH I118
J 2
(-2848 2375);
DISPLAY 0.872340 (-2848 2375);
PAINT GREEN (-2848 2375);
DISPLAY INVISIBLE (-2848 2375);
FORCEADD TAP..6
R 2
(-2850 2525);
FORCEPROP 3 LASTPIN (-2900 2525) SIG_NAME M_G_MA<12>
J 0
(-2890 2535);
DISPLAY 0.659574 (-2890 2535);
PAINT MONO (-2890 2535);
DISPLAY INVISIBLE (-2890 2535);
FORCEPROP 1 LASTPIN (-2900 2525) BN 12
J 2
(-2848 2533);
DISPLAY 0.617021 (-2848 2533);
PAINT GREEN (-2848 2533);
FORCEPROP 2 LAST CDS_LIB mstr_standard
J 0
(-2850 2525);
PAINT MONO (-2850 2525);
DISPLAY INVISIBLE (-2850 2525);
FORCEPROP 1 LAST BODY_TYPE PLUMBING
J 2
(-2850 2475);
DISPLAY 1.595745 (-2850 2475);
PAINT GREEN (-2850 2475);
DISPLAY INVISIBLE (-2850 2475);
FORCEPROP 1 LAST HDL_TAP TRUE
J 2
(-3175 2400);
DISPLAY 1.595745 (-3175 2400);
PAINT GREEN (-3175 2400);
DISPLAY INVISIBLE (-3175 2400);
FORCEPROP 1 LAST PATH I119
J 2
(-2848 2525);
DISPLAY 0.872340 (-2848 2525);
PAINT GREEN (-2848 2525);
DISPLAY INVISIBLE (-2848 2525);
FORCEADD TAP..6
(-5575 975);
FORCEPROP 3 LASTPIN (-5525 975) SIG_NAME M_G_CLK_DP<3>
J 0
(-5515 985);
DISPLAY 0.659574 (-5515 985);
PAINT MONO (-5515 985);
DISPLAY INVISIBLE (-5515 985);
FORCEPROP 1 LASTPIN (-5525 975) BN 3
J 0
(-5577 983);
DISPLAY 0.617021 (-5577 983);
PAINT GREEN (-5577 983);
FORCEPROP 2 LAST CDS_LIB mstr_standard
J 0
(-5575 975);
PAINT MONO (-5575 975);
DISPLAY INVISIBLE (-5575 975);
FORCEPROP 1 LAST BODY_TYPE PLUMBING
J 0
(-5575 925);
DISPLAY 1.595745 (-5575 925);
PAINT GREEN (-5575 925);
DISPLAY INVISIBLE (-5575 925);
FORCEPROP 1 LAST HDL_TAP TRUE
J 0
(-5250 850);
DISPLAY 1.595745 (-5250 850);
PAINT GREEN (-5250 850);
DISPLAY INVISIBLE (-5250 850);
FORCEPROP 1 LAST PATH I12
J 0
(-5577 975);
DISPLAY 0.872340 (-5577 975);
PAINT GREEN (-5577 975);
DISPLAY INVISIBLE (-5577 975);
FORCEADD TAP..6
R 2
(-2850 2575);
FORCEPROP 3 LASTPIN (-2900 2575) SIG_NAME M_G_MA<13>
J 0
(-2890 2585);
DISPLAY 0.659574 (-2890 2585);
PAINT MONO (-2890 2585);
DISPLAY INVISIBLE (-2890 2585);
FORCEPROP 1 LASTPIN (-2900 2575) BN 13
J 2
(-2848 2583);
DISPLAY 0.617021 (-2848 2583);
PAINT GREEN (-2848 2583);
FORCEPROP 2 LAST CDS_LIB mstr_standard
J 0
(-2850 2575);
PAINT MONO (-2850 2575);
DISPLAY INVISIBLE (-2850 2575);
FORCEPROP 1 LAST BODY_TYPE PLUMBING
J 2
(-2850 2525);
DISPLAY 1.595745 (-2850 2525);
PAINT GREEN (-2850 2525);
DISPLAY INVISIBLE (-2850 2525);
FORCEPROP 1 LAST HDL_TAP TRUE
J 2
(-3175 2450);
DISPLAY 1.595745 (-3175 2450);
PAINT GREEN (-3175 2450);
DISPLAY INVISIBLE (-3175 2450);
FORCEPROP 1 LAST PATH I120
J 2
(-2848 2575);
DISPLAY 0.872340 (-2848 2575);
PAINT GREEN (-2848 2575);
DISPLAY INVISIBLE (-2848 2575);
FORCEADD TAP..6
R 2
(-2850 2625);
FORCEPROP 3 LASTPIN (-2900 2625) SIG_NAME M_G_MA<14>
J 0
(-2890 2635);
DISPLAY 0.659574 (-2890 2635);
PAINT MONO (-2890 2635);
DISPLAY INVISIBLE (-2890 2635);
FORCEPROP 1 LASTPIN (-2900 2625) BN 14
J 2
(-2848 2633);
DISPLAY 0.617021 (-2848 2633);
PAINT GREEN (-2848 2633);
FORCEPROP 2 LAST CDS_LIB mstr_standard
J 0
(-2850 2625);
PAINT MONO (-2850 2625);
DISPLAY INVISIBLE (-2850 2625);
FORCEPROP 1 LAST BODY_TYPE PLUMBING
J 2
(-2850 2575);
DISPLAY 1.595745 (-2850 2575);
PAINT GREEN (-2850 2575);
DISPLAY INVISIBLE (-2850 2575);
FORCEPROP 1 LAST HDL_TAP TRUE
J 2
(-3175 2500);
DISPLAY 1.595745 (-3175 2500);
PAINT GREEN (-3175 2500);
DISPLAY INVISIBLE (-3175 2500);
FORCEPROP 1 LAST PATH I121
J 2
(-2848 2625);
DISPLAY 0.872340 (-2848 2625);
PAINT GREEN (-2848 2625);
DISPLAY INVISIBLE (-2848 2625);
FORCEADD TAP..6
R 2
(-2850 2675);
FORCEPROP 3 LASTPIN (-2900 2675) SIG_NAME M_G_MA<15>
J 0
(-2890 2685);
DISPLAY 0.659574 (-2890 2685);
PAINT MONO (-2890 2685);
DISPLAY INVISIBLE (-2890 2685);
FORCEPROP 1 LASTPIN (-2900 2675) BN 15
J 2
(-2848 2683);
DISPLAY 0.617021 (-2848 2683);
PAINT GREEN (-2848 2683);
FORCEPROP 2 LAST CDS_LIB mstr_standard
J 0
(-2850 2675);
PAINT MONO (-2850 2675);
DISPLAY INVISIBLE (-2850 2675);
FORCEPROP 1 LAST BODY_TYPE PLUMBING
J 2
(-2850 2625);
DISPLAY 1.595745 (-2850 2625);
PAINT GREEN (-2850 2625);
DISPLAY INVISIBLE (-2850 2625);
FORCEPROP 1 LAST HDL_TAP TRUE
J 2
(-3175 2550);
DISPLAY 1.595745 (-3175 2550);
PAINT GREEN (-3175 2550);
DISPLAY INVISIBLE (-3175 2550);
FORCEPROP 1 LAST PATH I122
J 2
(-2848 2675);
DISPLAY 0.872340 (-2848 2675);
PAINT GREEN (-2848 2675);
DISPLAY INVISIBLE (-2848 2675);
FORCEADD TAP..6
R 2
(-2850 2725);
FORCEPROP 3 LASTPIN (-2900 2725) SIG_NAME M_G_MA<16>
J 0
(-2890 2735);
DISPLAY 0.659574 (-2890 2735);
PAINT MONO (-2890 2735);
DISPLAY INVISIBLE (-2890 2735);
FORCEPROP 1 LASTPIN (-2900 2725) BN 16
J 2
(-2848 2733);
DISPLAY 0.617021 (-2848 2733);
PAINT GREEN (-2848 2733);
FORCEPROP 2 LAST CDS_LIB mstr_standard
J 0
(-2850 2725);
PAINT MONO (-2850 2725);
DISPLAY INVISIBLE (-2850 2725);
FORCEPROP 1 LAST BODY_TYPE PLUMBING
J 2
(-2850 2675);
DISPLAY 1.595745 (-2850 2675);
PAINT GREEN (-2850 2675);
DISPLAY INVISIBLE (-2850 2675);
FORCEPROP 1 LAST HDL_TAP TRUE
J 2
(-3175 2600);
DISPLAY 1.595745 (-3175 2600);
PAINT GREEN (-3175 2600);
DISPLAY INVISIBLE (-3175 2600);
FORCEPROP 1 LAST PATH I123
J 2
(-2848 2725);
DISPLAY 0.872340 (-2848 2725);
PAINT GREEN (-2848 2725);
DISPLAY INVISIBLE (-2848 2725);
FORCEADD TAP..6
R 2
(-2850 2775);
FORCEPROP 3 LASTPIN (-2900 2775) SIG_NAME M_G_MA<17>
J 0
(-2890 2785);
DISPLAY 0.659574 (-2890 2785);
PAINT MONO (-2890 2785);
DISPLAY INVISIBLE (-2890 2785);
FORCEPROP 1 LASTPIN (-2900 2775) BN 17
J 2
(-2848 2783);
DISPLAY 0.617021 (-2848 2783);
PAINT GREEN (-2848 2783);
FORCEPROP 2 LAST CDS_LIB mstr_standard
J 0
(-2850 2775);
PAINT MONO (-2850 2775);
DISPLAY INVISIBLE (-2850 2775);
FORCEPROP 1 LAST BODY_TYPE PLUMBING
J 2
(-2850 2725);
DISPLAY 1.595745 (-2850 2725);
PAINT GREEN (-2850 2725);
DISPLAY INVISIBLE (-2850 2725);
FORCEPROP 1 LAST HDL_TAP TRUE
J 2
(-3175 2650);
DISPLAY 1.595745 (-3175 2650);
PAINT GREEN (-3175 2650);
DISPLAY INVISIBLE (-3175 2650);
FORCEPROP 1 LAST PATH I124
J 2
(-2848 2775);
DISPLAY 0.872340 (-2848 2775);
PAINT GREEN (-2848 2775);
DISPLAY INVISIBLE (-2848 2775);
FORCEADD TAP..6
R 2
(-2850 2925);
FORCEPROP 3 LASTPIN (-2900 2925) SIG_NAME M_G_DQS_DN<1>
J 0
(-2890 2935);
DISPLAY 0.659574 (-2890 2935);
PAINT MONO (-2890 2935);
DISPLAY INVISIBLE (-2890 2935);
FORCEPROP 1 LASTPIN (-2900 2925) BN 1
J 2
(-2848 2933);
DISPLAY 0.617021 (-2848 2933);
PAINT GREEN (-2848 2933);
FORCEPROP 2 LAST CDS_LIB mstr_standard
J 0
(-2850 2925);
PAINT MONO (-2850 2925);
DISPLAY INVISIBLE (-2850 2925);
FORCEPROP 1 LAST BODY_TYPE PLUMBING
J 2
(-2850 2875);
DISPLAY 1.595745 (-2850 2875);
PAINT GREEN (-2850 2875);
DISPLAY INVISIBLE (-2850 2875);
FORCEPROP 1 LAST HDL_TAP TRUE
J 2
(-3175 2800);
DISPLAY 1.595745 (-3175 2800);
PAINT GREEN (-3175 2800);
DISPLAY INVISIBLE (-3175 2800);
FORCEPROP 1 LAST PATH I125
J 2
(-2848 2925);
DISPLAY 0.872340 (-2848 2925);
PAINT GREEN (-2848 2925);
DISPLAY INVISIBLE (-2848 2925);
FORCEADD TAP..6
R 2
(-2850 2975);
FORCEPROP 3 LASTPIN (-2900 2975) SIG_NAME M_G_DQS_DN<2>
J 0
(-2890 2985);
DISPLAY 0.659574 (-2890 2985);
PAINT MONO (-2890 2985);
DISPLAY INVISIBLE (-2890 2985);
FORCEPROP 1 LASTPIN (-2900 2975) BN 2
J 2
(-2848 2983);
DISPLAY 0.617021 (-2848 2983);
PAINT GREEN (-2848 2983);
FORCEPROP 2 LAST CDS_LIB mstr_standard
J 0
(-2850 2975);
PAINT MONO (-2850 2975);
DISPLAY INVISIBLE (-2850 2975);
FORCEPROP 1 LAST BODY_TYPE PLUMBING
J 2
(-2850 2925);
DISPLAY 1.595745 (-2850 2925);
PAINT GREEN (-2850 2925);
DISPLAY INVISIBLE (-2850 2925);
FORCEPROP 1 LAST HDL_TAP TRUE
J 2
(-3175 2850);
DISPLAY 1.595745 (-3175 2850);
PAINT GREEN (-3175 2850);
DISPLAY INVISIBLE (-3175 2850);
FORCEPROP 1 LAST PATH I126
J 2
(-2848 2975);
DISPLAY 0.872340 (-2848 2975);
PAINT GREEN (-2848 2975);
DISPLAY INVISIBLE (-2848 2975);
FORCEADD TAP..6
R 2
(-2850 2875);
FORCEPROP 3 LASTPIN (-2900 2875) SIG_NAME M_G_DQS_DN<0>
J 0
(-2890 2885);
DISPLAY 0.659574 (-2890 2885);
PAINT MONO (-2890 2885);
DISPLAY INVISIBLE (-2890 2885);
FORCEPROP 1 LASTPIN (-2900 2875) BN 0
J 2
(-2848 2883);
DISPLAY 0.617021 (-2848 2883);
PAINT GREEN (-2848 2883);
FORCEPROP 2 LAST CDS_LIB mstr_standard
J 0
(-2850 2875);
PAINT MONO (-2850 2875);
DISPLAY INVISIBLE (-2850 2875);
FORCEPROP 1 LAST BODY_TYPE PLUMBING
J 2
(-2850 2825);
DISPLAY 1.595745 (-2850 2825);
PAINT GREEN (-2850 2825);
DISPLAY INVISIBLE (-2850 2825);
FORCEPROP 1 LAST HDL_TAP TRUE
J 2
(-3175 2750);
DISPLAY 1.595745 (-3175 2750);
PAINT GREEN (-3175 2750);
DISPLAY INVISIBLE (-3175 2750);
FORCEPROP 1 LAST PATH I127
J 2
(-2848 2875);
DISPLAY 0.872340 (-2848 2875);
PAINT GREEN (-2848 2875);
DISPLAY INVISIBLE (-2848 2875);
FORCEADD TAP..6
R 2
(-2850 3075);
FORCEPROP 3 LASTPIN (-2900 3075) SIG_NAME M_G_DQS_DN<4>
J 0
(-2890 3085);
DISPLAY 0.659574 (-2890 3085);
PAINT MONO (-2890 3085);
DISPLAY INVISIBLE (-2890 3085);
FORCEPROP 1 LASTPIN (-2900 3075) BN 4
J 2
(-2848 3083);
DISPLAY 0.617021 (-2848 3083);
PAINT GREEN (-2848 3083);
FORCEPROP 2 LAST CDS_LIB mstr_standard
J 0
(-2850 3075);
PAINT MONO (-2850 3075);
DISPLAY INVISIBLE (-2850 3075);
FORCEPROP 1 LAST BODY_TYPE PLUMBING
J 2
(-2850 3025);
DISPLAY 1.595745 (-2850 3025);
PAINT GREEN (-2850 3025);
DISPLAY INVISIBLE (-2850 3025);
FORCEPROP 1 LAST HDL_TAP TRUE
J 2
(-3175 2950);
DISPLAY 1.595745 (-3175 2950);
PAINT GREEN (-3175 2950);
DISPLAY INVISIBLE (-3175 2950);
FORCEPROP 1 LAST PATH I128
J 2
(-2848 3075);
DISPLAY 0.872340 (-2848 3075);
PAINT GREEN (-2848 3075);
DISPLAY INVISIBLE (-2848 3075);
FORCEADD TAP..6
R 2
(-2850 3025);
FORCEPROP 3 LASTPIN (-2900 3025) SIG_NAME M_G_DQS_DN<3>
J 0
(-2890 3035);
DISPLAY 0.659574 (-2890 3035);
PAINT MONO (-2890 3035);
DISPLAY INVISIBLE (-2890 3035);
FORCEPROP 1 LASTPIN (-2900 3025) BN 3
J 2
(-2848 3033);
DISPLAY 0.617021 (-2848 3033);
PAINT GREEN (-2848 3033);
FORCEPROP 2 LAST CDS_LIB mstr_standard
J 0
(-2850 3025);
PAINT MONO (-2850 3025);
DISPLAY INVISIBLE (-2850 3025);
FORCEPROP 1 LAST BODY_TYPE PLUMBING
J 2
(-2850 2975);
DISPLAY 1.595745 (-2850 2975);
PAINT GREEN (-2850 2975);
DISPLAY INVISIBLE (-2850 2975);
FORCEPROP 1 LAST HDL_TAP TRUE
J 2
(-3175 2900);
DISPLAY 1.595745 (-3175 2900);
PAINT GREEN (-3175 2900);
DISPLAY INVISIBLE (-3175 2900);
FORCEPROP 1 LAST PATH I129
J 2
(-2848 3025);
DISPLAY 0.872340 (-2848 3025);
PAINT GREEN (-2848 3025);
DISPLAY INVISIBLE (-2848 3025);
FORCEADD TAP..6
(-5575 1075);
FORCEPROP 3 LASTPIN (-5525 1075) SIG_NAME M_G_ECC<0>
J 0
(-5515 1085);
DISPLAY 0.659574 (-5515 1085);
PAINT MONO (-5515 1085);
DISPLAY INVISIBLE (-5515 1085);
FORCEPROP 1 LASTPIN (-5525 1075) BN 0
J 0
(-5577 1083);
DISPLAY 0.617021 (-5577 1083);
PAINT GREEN (-5577 1083);
FORCEPROP 2 LAST CDS_LIB mstr_standard
J 0
(-5575 1075);
PAINT MONO (-5575 1075);
DISPLAY INVISIBLE (-5575 1075);
FORCEPROP 1 LAST BODY_TYPE PLUMBING
J 0
(-5575 1025);
DISPLAY 1.595745 (-5575 1025);
PAINT GREEN (-5575 1025);
DISPLAY INVISIBLE (-5575 1025);
FORCEPROP 1 LAST HDL_TAP TRUE
J 0
(-5250 950);
DISPLAY 1.595745 (-5250 950);
PAINT GREEN (-5250 950);
DISPLAY INVISIBLE (-5250 950);
FORCEPROP 1 LAST PATH I13
J 0
(-5577 1075);
DISPLAY 0.872340 (-5577 1075);
PAINT GREEN (-5577 1075);
DISPLAY INVISIBLE (-5577 1075);
FORCEADD TAP..6
R 2
(-2850 3125);
FORCEPROP 3 LASTPIN (-2900 3125) SIG_NAME M_G_DQS_DN<5>
J 0
(-2890 3135);
DISPLAY 0.659574 (-2890 3135);
PAINT MONO (-2890 3135);
DISPLAY INVISIBLE (-2890 3135);
FORCEPROP 1 LASTPIN (-2900 3125) BN 5
J 2
(-2848 3133);
DISPLAY 0.617021 (-2848 3133);
PAINT GREEN (-2848 3133);
FORCEPROP 2 LAST CDS_LIB mstr_standard
J 0
(-2850 3125);
PAINT MONO (-2850 3125);
DISPLAY INVISIBLE (-2850 3125);
FORCEPROP 1 LAST BODY_TYPE PLUMBING
J 2
(-2850 3075);
DISPLAY 1.595745 (-2850 3075);
PAINT GREEN (-2850 3075);
DISPLAY INVISIBLE (-2850 3075);
FORCEPROP 1 LAST HDL_TAP TRUE
J 2
(-3175 3000);
DISPLAY 1.595745 (-3175 3000);
PAINT GREEN (-3175 3000);
DISPLAY INVISIBLE (-3175 3000);
FORCEPROP 1 LAST PATH I130
J 2
(-2848 3125);
DISPLAY 0.872340 (-2848 3125);
PAINT GREEN (-2848 3125);
DISPLAY INVISIBLE (-2848 3125);
FORCEADD TAP..6
R 2
(-2850 3175);
FORCEPROP 3 LASTPIN (-2900 3175) SIG_NAME M_G_DQS_DN<6>
J 0
(-2890 3185);
DISPLAY 0.659574 (-2890 3185);
PAINT MONO (-2890 3185);
DISPLAY INVISIBLE (-2890 3185);
FORCEPROP 1 LASTPIN (-2900 3175) BN 6
J 2
(-2848 3183);
DISPLAY 0.617021 (-2848 3183);
PAINT GREEN (-2848 3183);
FORCEPROP 2 LAST CDS_LIB mstr_standard
J 0
(-2850 3175);
PAINT MONO (-2850 3175);
DISPLAY INVISIBLE (-2850 3175);
FORCEPROP 1 LAST BODY_TYPE PLUMBING
J 2
(-2850 3125);
DISPLAY 1.595745 (-2850 3125);
PAINT GREEN (-2850 3125);
DISPLAY INVISIBLE (-2850 3125);
FORCEPROP 1 LAST HDL_TAP TRUE
J 2
(-3175 3050);
DISPLAY 1.595745 (-3175 3050);
PAINT GREEN (-3175 3050);
DISPLAY INVISIBLE (-3175 3050);
FORCEPROP 1 LAST PATH I131
J 2
(-2848 3175);
DISPLAY 0.872340 (-2848 3175);
PAINT GREEN (-2848 3175);
DISPLAY INVISIBLE (-2848 3175);
FORCEADD TAP..6
R 2
(-2850 3225);
FORCEPROP 3 LASTPIN (-2900 3225) SIG_NAME M_G_DQS_DN<7>
J 0
(-2890 3235);
DISPLAY 0.659574 (-2890 3235);
PAINT MONO (-2890 3235);
DISPLAY INVISIBLE (-2890 3235);
FORCEPROP 1 LASTPIN (-2900 3225) BN 7
J 2
(-2848 3233);
DISPLAY 0.617021 (-2848 3233);
PAINT GREEN (-2848 3233);
FORCEPROP 2 LAST CDS_LIB mstr_standard
J 0
(-2850 3225);
PAINT MONO (-2850 3225);
DISPLAY INVISIBLE (-2850 3225);
FORCEPROP 1 LAST BODY_TYPE PLUMBING
J 2
(-2850 3175);
DISPLAY 1.595745 (-2850 3175);
PAINT GREEN (-2850 3175);
DISPLAY INVISIBLE (-2850 3175);
FORCEPROP 1 LAST HDL_TAP TRUE
J 2
(-3175 3100);
DISPLAY 1.595745 (-3175 3100);
PAINT GREEN (-3175 3100);
DISPLAY INVISIBLE (-3175 3100);
FORCEPROP 1 LAST PATH I132
J 2
(-2848 3225);
DISPLAY 0.872340 (-2848 3225);
PAINT GREEN (-2848 3225);
DISPLAY INVISIBLE (-2848 3225);
FORCEADD TAP..6
R 2
(-2850 3275);
FORCEPROP 3 LASTPIN (-2900 3275) SIG_NAME M_G_DQS_DN<8>
J 0
(-2890 3285);
DISPLAY 0.659574 (-2890 3285);
PAINT MONO (-2890 3285);
DISPLAY INVISIBLE (-2890 3285);
FORCEPROP 1 LASTPIN (-2900 3275) BN 8
J 2
(-2848 3283);
DISPLAY 0.617021 (-2848 3283);
PAINT GREEN (-2848 3283);
FORCEPROP 2 LAST CDS_LIB mstr_standard
J 0
(-2850 3275);
PAINT MONO (-2850 3275);
DISPLAY INVISIBLE (-2850 3275);
FORCEPROP 1 LAST BODY_TYPE PLUMBING
J 2
(-2850 3225);
DISPLAY 1.595745 (-2850 3225);
PAINT GREEN (-2850 3225);
DISPLAY INVISIBLE (-2850 3225);
FORCEPROP 1 LAST HDL_TAP TRUE
J 2
(-3175 3150);
DISPLAY 1.595745 (-3175 3150);
PAINT GREEN (-3175 3150);
DISPLAY INVISIBLE (-3175 3150);
FORCEPROP 1 LAST PATH I133
J 2
(-2848 3275);
DISPLAY 0.872340 (-2848 3275);
PAINT GREEN (-2848 3275);
DISPLAY INVISIBLE (-2848 3275);
FORCEADD TAP..6
R 2
(-2850 3325);
FORCEPROP 3 LASTPIN (-2900 3325) SIG_NAME M_G_DQS_DN<9>
J 0
(-2890 3335);
DISPLAY 0.659574 (-2890 3335);
PAINT MONO (-2890 3335);
DISPLAY INVISIBLE (-2890 3335);
FORCEPROP 1 LASTPIN (-2900 3325) BN 9
J 2
(-2848 3333);
DISPLAY 0.617021 (-2848 3333);
PAINT GREEN (-2848 3333);
FORCEPROP 2 LAST CDS_LIB mstr_standard
J 0
(-2850 3325);
PAINT MONO (-2850 3325);
DISPLAY INVISIBLE (-2850 3325);
FORCEPROP 1 LAST BODY_TYPE PLUMBING
J 2
(-2850 3275);
DISPLAY 1.595745 (-2850 3275);
PAINT GREEN (-2850 3275);
DISPLAY INVISIBLE (-2850 3275);
FORCEPROP 1 LAST HDL_TAP TRUE
J 2
(-3175 3200);
DISPLAY 1.595745 (-3175 3200);
PAINT GREEN (-3175 3200);
DISPLAY INVISIBLE (-3175 3200);
FORCEPROP 1 LAST PATH I134
J 2
(-2848 3325);
DISPLAY 0.872340 (-2848 3325);
PAINT GREEN (-2848 3325);
DISPLAY INVISIBLE (-2848 3325);
FORCEADD TAP..6
R 2
(-2850 3375);
FORCEPROP 3 LASTPIN (-2900 3375) SIG_NAME M_G_DQS_DN<10>
J 0
(-2890 3385);
DISPLAY 0.659574 (-2890 3385);
PAINT MONO (-2890 3385);
DISPLAY INVISIBLE (-2890 3385);
FORCEPROP 1 LASTPIN (-2900 3375) BN 10
J 2
(-2848 3383);
DISPLAY 0.617021 (-2848 3383);
PAINT GREEN (-2848 3383);
FORCEPROP 2 LAST CDS_LIB mstr_standard
J 0
(-2850 3375);
PAINT MONO (-2850 3375);
DISPLAY INVISIBLE (-2850 3375);
FORCEPROP 1 LAST BODY_TYPE PLUMBING
J 2
(-2850 3325);
DISPLAY 1.595745 (-2850 3325);
PAINT GREEN (-2850 3325);
DISPLAY INVISIBLE (-2850 3325);
FORCEPROP 1 LAST HDL_TAP TRUE
J 2
(-3175 3250);
DISPLAY 1.595745 (-3175 3250);
PAINT GREEN (-3175 3250);
DISPLAY INVISIBLE (-3175 3250);
FORCEPROP 1 LAST PATH I135
J 2
(-2848 3375);
DISPLAY 0.872340 (-2848 3375);
PAINT GREEN (-2848 3375);
DISPLAY INVISIBLE (-2848 3375);
FORCEADD TAP..6
R 2
(-2850 3475);
FORCEPROP 3 LASTPIN (-2900 3475) SIG_NAME M_G_DQS_DN<12>
J 0
(-2890 3485);
DISPLAY 0.659574 (-2890 3485);
PAINT MONO (-2890 3485);
DISPLAY INVISIBLE (-2890 3485);
FORCEPROP 1 LASTPIN (-2900 3475) BN 12
J 2
(-2848 3483);
DISPLAY 0.617021 (-2848 3483);
PAINT GREEN (-2848 3483);
FORCEPROP 2 LAST CDS_LIB mstr_standard
J 0
(-2850 3475);
PAINT MONO (-2850 3475);
DISPLAY INVISIBLE (-2850 3475);
FORCEPROP 1 LAST BODY_TYPE PLUMBING
J 2
(-2850 3425);
DISPLAY 1.595745 (-2850 3425);
PAINT GREEN (-2850 3425);
DISPLAY INVISIBLE (-2850 3425);
FORCEPROP 1 LAST HDL_TAP TRUE
J 2
(-3175 3350);
DISPLAY 1.595745 (-3175 3350);
PAINT GREEN (-3175 3350);
DISPLAY INVISIBLE (-3175 3350);
FORCEPROP 1 LAST PATH I136
J 2
(-2848 3475);
DISPLAY 0.872340 (-2848 3475);
PAINT GREEN (-2848 3475);
DISPLAY INVISIBLE (-2848 3475);
FORCEADD TAP..6
R 2
(-2850 3425);
FORCEPROP 3 LASTPIN (-2900 3425) SIG_NAME M_G_DQS_DN<11>
J 0
(-2890 3435);
DISPLAY 0.659574 (-2890 3435);
PAINT MONO (-2890 3435);
DISPLAY INVISIBLE (-2890 3435);
FORCEPROP 1 LASTPIN (-2900 3425) BN 11
J 2
(-2848 3433);
DISPLAY 0.617021 (-2848 3433);
PAINT GREEN (-2848 3433);
FORCEPROP 2 LAST CDS_LIB mstr_standard
J 0
(-2850 3425);
PAINT MONO (-2850 3425);
DISPLAY INVISIBLE (-2850 3425);
FORCEPROP 1 LAST BODY_TYPE PLUMBING
J 2
(-2850 3375);
DISPLAY 1.595745 (-2850 3375);
PAINT GREEN (-2850 3375);
DISPLAY INVISIBLE (-2850 3375);
FORCEPROP 1 LAST HDL_TAP TRUE
J 2
(-3175 3300);
DISPLAY 1.595745 (-3175 3300);
PAINT GREEN (-3175 3300);
DISPLAY INVISIBLE (-3175 3300);
FORCEPROP 1 LAST PATH I137
J 2
(-2848 3425);
DISPLAY 0.872340 (-2848 3425);
PAINT GREEN (-2848 3425);
DISPLAY INVISIBLE (-2848 3425);
FORCEADD TAP..6
R 2
(-2850 3625);
FORCEPROP 3 LASTPIN (-2900 3625) SIG_NAME M_G_DQS_DN<15>
J 0
(-2890 3635);
DISPLAY 0.659574 (-2890 3635);
PAINT MONO (-2890 3635);
DISPLAY INVISIBLE (-2890 3635);
FORCEPROP 1 LASTPIN (-2900 3625) BN 15
J 2
(-2848 3633);
DISPLAY 0.617021 (-2848 3633);
PAINT GREEN (-2848 3633);
FORCEPROP 2 LAST CDS_LIB mstr_standard
J 0
(-2850 3625);
PAINT MONO (-2850 3625);
DISPLAY INVISIBLE (-2850 3625);
FORCEPROP 1 LAST BODY_TYPE PLUMBING
J 2
(-2850 3575);
DISPLAY 1.595745 (-2850 3575);
PAINT GREEN (-2850 3575);
DISPLAY INVISIBLE (-2850 3575);
FORCEPROP 1 LAST HDL_TAP TRUE
J 2
(-3175 3500);
DISPLAY 1.595745 (-3175 3500);
PAINT GREEN (-3175 3500);
DISPLAY INVISIBLE (-3175 3500);
FORCEPROP 1 LAST PATH I138
J 2
(-2848 3625);
DISPLAY 0.872340 (-2848 3625);
PAINT GREEN (-2848 3625);
DISPLAY INVISIBLE (-2848 3625);
FORCEADD TAP..6
R 2
(-2850 3575);
FORCEPROP 3 LASTPIN (-2900 3575) SIG_NAME M_G_DQS_DN<14>
J 0
(-2890 3585);
DISPLAY 0.659574 (-2890 3585);
PAINT MONO (-2890 3585);
DISPLAY INVISIBLE (-2890 3585);
FORCEPROP 1 LASTPIN (-2900 3575) BN 14
J 2
(-2848 3583);
DISPLAY 0.617021 (-2848 3583);
PAINT GREEN (-2848 3583);
FORCEPROP 2 LAST CDS_LIB mstr_standard
J 0
(-2850 3575);
PAINT MONO (-2850 3575);
DISPLAY INVISIBLE (-2850 3575);
FORCEPROP 1 LAST BODY_TYPE PLUMBING
J 2
(-2850 3525);
DISPLAY 1.595745 (-2850 3525);
PAINT GREEN (-2850 3525);
DISPLAY INVISIBLE (-2850 3525);
FORCEPROP 1 LAST HDL_TAP TRUE
J 2
(-3175 3450);
DISPLAY 1.595745 (-3175 3450);
PAINT GREEN (-3175 3450);
DISPLAY INVISIBLE (-3175 3450);
FORCEPROP 1 LAST PATH I139
J 2
(-2848 3575);
DISPLAY 0.872340 (-2848 3575);
PAINT GREEN (-2848 3575);
DISPLAY INVISIBLE (-2848 3575);
FORCEADD TAP..6
(-5575 1125);
FORCEPROP 3 LASTPIN (-5525 1125) SIG_NAME M_G_ECC<1>
J 0
(-5515 1135);
DISPLAY 0.659574 (-5515 1135);
PAINT MONO (-5515 1135);
DISPLAY INVISIBLE (-5515 1135);
FORCEPROP 1 LASTPIN (-5525 1125) BN 1
J 0
(-5577 1133);
DISPLAY 0.617021 (-5577 1133);
PAINT GREEN (-5577 1133);
FORCEPROP 2 LAST CDS_LIB mstr_standard
J 0
(-5575 1125);
PAINT MONO (-5575 1125);
DISPLAY INVISIBLE (-5575 1125);
FORCEPROP 1 LAST BODY_TYPE PLUMBING
J 0
(-5575 1075);
DISPLAY 1.595745 (-5575 1075);
PAINT GREEN (-5575 1075);
DISPLAY INVISIBLE (-5575 1075);
FORCEPROP 1 LAST HDL_TAP TRUE
J 0
(-5250 1000);
DISPLAY 1.595745 (-5250 1000);
PAINT GREEN (-5250 1000);
DISPLAY INVISIBLE (-5250 1000);
FORCEPROP 1 LAST PATH I14
J 0
(-5577 1125);
DISPLAY 0.872340 (-5577 1125);
PAINT GREEN (-5577 1125);
DISPLAY INVISIBLE (-5577 1125);
FORCEADD TAP..6
R 2
(-2850 3525);
FORCEPROP 3 LASTPIN (-2900 3525) SIG_NAME M_G_DQS_DN<13>
J 0
(-2890 3535);
DISPLAY 0.659574 (-2890 3535);
PAINT MONO (-2890 3535);
DISPLAY INVISIBLE (-2890 3535);
FORCEPROP 1 LASTPIN (-2900 3525) BN 13
J 2
(-2848 3533);
DISPLAY 0.617021 (-2848 3533);
PAINT GREEN (-2848 3533);
FORCEPROP 2 LAST CDS_LIB mstr_standard
J 0
(-2850 3525);
PAINT MONO (-2850 3525);
DISPLAY INVISIBLE (-2850 3525);
FORCEPROP 1 LAST BODY_TYPE PLUMBING
J 2
(-2850 3475);
DISPLAY 1.595745 (-2850 3475);
PAINT GREEN (-2850 3475);
DISPLAY INVISIBLE (-2850 3475);
FORCEPROP 1 LAST HDL_TAP TRUE
J 2
(-3175 3400);
DISPLAY 1.595745 (-3175 3400);
PAINT GREEN (-3175 3400);
DISPLAY INVISIBLE (-3175 3400);
FORCEPROP 1 LAST PATH I140
J 2
(-2848 3525);
DISPLAY 0.872340 (-2848 3525);
PAINT GREEN (-2848 3525);
DISPLAY INVISIBLE (-2848 3525);
FORCEADD TAP..6
R 2
(-2850 3675);
FORCEPROP 3 LASTPIN (-2900 3675) SIG_NAME M_G_DQS_DN<16>
J 0
(-2890 3685);
DISPLAY 0.659574 (-2890 3685);
PAINT MONO (-2890 3685);
DISPLAY INVISIBLE (-2890 3685);
FORCEPROP 1 LASTPIN (-2900 3675) BN 16
J 2
(-2848 3683);
DISPLAY 0.617021 (-2848 3683);
PAINT GREEN (-2848 3683);
FORCEPROP 2 LAST CDS_LIB mstr_standard
J 0
(-2850 3675);
PAINT MONO (-2850 3675);
DISPLAY INVISIBLE (-2850 3675);
FORCEPROP 1 LAST BODY_TYPE PLUMBING
J 2
(-2850 3625);
DISPLAY 1.595745 (-2850 3625);
PAINT GREEN (-2850 3625);
DISPLAY INVISIBLE (-2850 3625);
FORCEPROP 1 LAST HDL_TAP TRUE
J 2
(-3175 3550);
DISPLAY 1.595745 (-3175 3550);
PAINT GREEN (-3175 3550);
DISPLAY INVISIBLE (-3175 3550);
FORCEPROP 1 LAST PATH I141
J 2
(-2848 3675);
DISPLAY 0.872340 (-2848 3675);
PAINT GREEN (-2848 3675);
DISPLAY INVISIBLE (-2848 3675);
FORCEADD TAP..6
R 2
(-2850 3725);
FORCEPROP 3 LASTPIN (-2900 3725) SIG_NAME M_G_DQS_DN<17>
J 0
(-2890 3735);
DISPLAY 0.659574 (-2890 3735);
PAINT MONO (-2890 3735);
DISPLAY INVISIBLE (-2890 3735);
FORCEPROP 1 LASTPIN (-2900 3725) BN 17
J 2
(-2848 3733);
DISPLAY 0.617021 (-2848 3733);
PAINT GREEN (-2848 3733);
FORCEPROP 2 LAST CDS_LIB mstr_standard
J 0
(-2850 3725);
PAINT MONO (-2850 3725);
DISPLAY INVISIBLE (-2850 3725);
FORCEPROP 1 LAST BODY_TYPE PLUMBING
J 2
(-2850 3675);
DISPLAY 1.595745 (-2850 3675);
PAINT GREEN (-2850 3675);
DISPLAY INVISIBLE (-2850 3675);
FORCEPROP 1 LAST HDL_TAP TRUE
J 2
(-3175 3600);
DISPLAY 1.595745 (-3175 3600);
PAINT GREEN (-3175 3600);
DISPLAY INVISIBLE (-3175 3600);
FORCEPROP 1 LAST PATH I142
J 2
(-2848 3725);
DISPLAY 0.872340 (-2848 3725);
PAINT GREEN (-2848 3725);
DISPLAY INVISIBLE (-2848 3725);
FORCEADD TAP..6
R 2
(-2850 3825);
FORCEPROP 3 LASTPIN (-2900 3825) SIG_NAME M_G_DQS_DP<0>
J 0
(-2890 3835);
DISPLAY 0.659574 (-2890 3835);
PAINT MONO (-2890 3835);
DISPLAY INVISIBLE (-2890 3835);
FORCEPROP 1 LASTPIN (-2900 3825) BN 0
J 2
(-2848 3833);
DISPLAY 0.617021 (-2848 3833);
PAINT GREEN (-2848 3833);
FORCEPROP 2 LAST CDS_LIB mstr_standard
J 0
(-2850 3825);
PAINT MONO (-2850 3825);
DISPLAY INVISIBLE (-2850 3825);
FORCEPROP 1 LAST BODY_TYPE PLUMBING
J 2
(-2850 3775);
DISPLAY 1.595745 (-2850 3775);
PAINT GREEN (-2850 3775);
DISPLAY INVISIBLE (-2850 3775);
FORCEPROP 1 LAST HDL_TAP TRUE
J 2
(-3175 3700);
DISPLAY 1.595745 (-3175 3700);
PAINT GREEN (-3175 3700);
DISPLAY INVISIBLE (-3175 3700);
FORCEPROP 1 LAST PATH I143
J 2
(-2848 3825);
DISPLAY 0.872340 (-2848 3825);
PAINT GREEN (-2848 3825);
DISPLAY INVISIBLE (-2848 3825);
FORCEADD TAP..6
R 2
(-2850 3875);
FORCEPROP 3 LASTPIN (-2900 3875) SIG_NAME M_G_DQS_DP<1>
J 0
(-2890 3885);
DISPLAY 0.659574 (-2890 3885);
PAINT MONO (-2890 3885);
DISPLAY INVISIBLE (-2890 3885);
FORCEPROP 1 LASTPIN (-2900 3875) BN 1
J 2
(-2848 3883);
DISPLAY 0.617021 (-2848 3883);
PAINT GREEN (-2848 3883);
FORCEPROP 2 LAST CDS_LIB mstr_standard
J 0
(-2850 3875);
PAINT MONO (-2850 3875);
DISPLAY INVISIBLE (-2850 3875);
FORCEPROP 1 LAST BODY_TYPE PLUMBING
J 2
(-2850 3825);
DISPLAY 1.595745 (-2850 3825);
PAINT GREEN (-2850 3825);
DISPLAY INVISIBLE (-2850 3825);
FORCEPROP 1 LAST HDL_TAP TRUE
J 2
(-3175 3750);
DISPLAY 1.595745 (-3175 3750);
PAINT GREEN (-3175 3750);
DISPLAY INVISIBLE (-3175 3750);
FORCEPROP 1 LAST PATH I144
J 2
(-2848 3875);
DISPLAY 0.872340 (-2848 3875);
PAINT GREEN (-2848 3875);
DISPLAY INVISIBLE (-2848 3875);
FORCEADD TAP..6
R 2
(-2850 3925);
FORCEPROP 3 LASTPIN (-2900 3925) SIG_NAME M_G_DQS_DP<2>
J 0
(-2890 3935);
DISPLAY 0.659574 (-2890 3935);
PAINT MONO (-2890 3935);
DISPLAY INVISIBLE (-2890 3935);
FORCEPROP 1 LASTPIN (-2900 3925) BN 2
J 2
(-2848 3933);
DISPLAY 0.617021 (-2848 3933);
PAINT GREEN (-2848 3933);
FORCEPROP 2 LAST CDS_LIB mstr_standard
J 0
(-2850 3925);
PAINT MONO (-2850 3925);
DISPLAY INVISIBLE (-2850 3925);
FORCEPROP 1 LAST BODY_TYPE PLUMBING
J 2
(-2850 3875);
DISPLAY 1.595745 (-2850 3875);
PAINT GREEN (-2850 3875);
DISPLAY INVISIBLE (-2850 3875);
FORCEPROP 1 LAST HDL_TAP TRUE
J 2
(-3175 3800);
DISPLAY 1.595745 (-3175 3800);
PAINT GREEN (-3175 3800);
DISPLAY INVISIBLE (-3175 3800);
FORCEPROP 1 LAST PATH I145
J 2
(-2848 3925);
DISPLAY 0.872340 (-2848 3925);
PAINT GREEN (-2848 3925);
DISPLAY INVISIBLE (-2848 3925);
FORCEADD TAP..6
R 2
(-2850 3975);
FORCEPROP 3 LASTPIN (-2900 3975) SIG_NAME M_G_DQS_DP<3>
J 0
(-2890 3985);
DISPLAY 0.659574 (-2890 3985);
PAINT MONO (-2890 3985);
DISPLAY INVISIBLE (-2890 3985);
FORCEPROP 1 LASTPIN (-2900 3975) BN 3
J 2
(-2848 3983);
DISPLAY 0.617021 (-2848 3983);
PAINT GREEN (-2848 3983);
FORCEPROP 2 LAST CDS_LIB mstr_standard
J 0
(-2850 3975);
PAINT MONO (-2850 3975);
DISPLAY INVISIBLE (-2850 3975);
FORCEPROP 1 LAST BODY_TYPE PLUMBING
J 2
(-2850 3925);
DISPLAY 1.595745 (-2850 3925);
PAINT GREEN (-2850 3925);
DISPLAY INVISIBLE (-2850 3925);
FORCEPROP 1 LAST HDL_TAP TRUE
J 2
(-3175 3850);
DISPLAY 1.595745 (-3175 3850);
PAINT GREEN (-3175 3850);
DISPLAY INVISIBLE (-3175 3850);
FORCEPROP 1 LAST PATH I146
J 2
(-2848 3975);
DISPLAY 0.872340 (-2848 3975);
PAINT GREEN (-2848 3975);
DISPLAY INVISIBLE (-2848 3975);
FORCEADD OFFPAGE..2
(-2000 525);
FORCEPROP 2 LAST $XR1 78 
J 0
(-1721 525);
DISPLAY 0.638298 (-1721 525);
PAINT MONO (-1721 525);
FORCEPROP 2 LAST $XR0 77 
J 0
(-1811 525);
DISPLAY 0.638298 (-1811 525);
PAINT MONO (-1811 525);
FORCEPROP 2 LAST CDS_LIB mstr_standard
J 0
(-2000 525);
PAINT MONO (-2000 525);
DISPLAY INVISIBLE (-2000 525);
FORCEPROP 1 LAST OFFPAGE TRUE
J 0
(-1675 400);
DISPLAY 1.170213 (-1675 400);
PAINT GREEN (-1675 400);
DISPLAY INVISIBLE (-1675 400);
FORCEPROP 1 LAST COMMENT_BODY TRUE
J 0
(-2045 430);
DISPLAY 1.170213 (-2045 430);
PAINT GREEN (-2045 430);
DISPLAY INVISIBLE (-2045 430);
FORCEPROP 2 LAST PATH I147
J 0
(-1825 600);
DISPLAY 1.021277 (-1825 600);
PAINT ORANGE (-1825 600);
DISPLAY INVISIBLE (-1825 600);
FORCEADD OFFPAGE..4
(-2000 575);
FORCEPROP 2 LAST $XR1 78 
J 0
(-1724 575);
DISPLAY 0.638298 (-1724 575);
PAINT MONO (-1724 575);
FORCEPROP 2 LAST $XR0 77 
J 0
(-1814 575);
DISPLAY 0.638298 (-1814 575);
PAINT MONO (-1814 575);
FORCEPROP 2 LAST CDS_LIB mstr_standard
J 0
(-2000 575);
PAINT MONO (-2000 575);
DISPLAY INVISIBLE (-2000 575);
FORCEPROP 1 LAST OFFPAGE TRUE
J 0
(-1675 450);
DISPLAY 1.170213 (-1675 450);
PAINT GREEN (-1675 450);
DISPLAY INVISIBLE (-1675 450);
FORCEPROP 1 LAST COMMENT_BODY TRUE
J 0
(-2025 475);
DISPLAY 1.170213 (-2025 475);
PAINT GREEN (-2025 475);
DISPLAY INVISIBLE (-2025 475);
FORCEPROP 2 LAST PATH I148
J 0
(-1825 650);
DISPLAY 1.021277 (-1825 650);
PAINT ORANGE (-1825 650);
DISPLAY INVISIBLE (-1825 650);
FORCEADD OFFPAGE..2
(-2000 625);
FORCEPROP 2 LAST $XR1 78 
J 0
(-1721 625);
DISPLAY 0.638298 (-1721 625);
PAINT MONO (-1721 625);
FORCEPROP 2 LAST $XR0 77 
J 0
(-1811 625);
DISPLAY 0.638298 (-1811 625);
PAINT MONO (-1811 625);
FORCEPROP 2 LAST CDS_LIB mstr_standard
J 0
(-2000 625);
PAINT MONO (-2000 625);
DISPLAY INVISIBLE (-2000 625);
FORCEPROP 1 LAST OFFPAGE TRUE
J 0
(-1675 500);
DISPLAY 1.170213 (-1675 500);
PAINT GREEN (-1675 500);
DISPLAY INVISIBLE (-1675 500);
FORCEPROP 1 LAST COMMENT_BODY TRUE
J 0
(-2045 530);
DISPLAY 1.170213 (-2045 530);
PAINT GREEN (-2045 530);
DISPLAY INVISIBLE (-2045 530);
FORCEPROP 2 LAST PATH I149
J 0
(-1825 700);
DISPLAY 1.021277 (-1825 700);
PAINT ORANGE (-1825 700);
DISPLAY INVISIBLE (-1825 700);
FORCEADD TAP..6
(-5575 1175);
FORCEPROP 3 LASTPIN (-5525 1175) SIG_NAME M_G_ECC<2>
J 0
(-5515 1185);
DISPLAY 0.659574 (-5515 1185);
PAINT MONO (-5515 1185);
DISPLAY INVISIBLE (-5515 1185);
FORCEPROP 1 LASTPIN (-5525 1175) BN 2
J 0
(-5577 1183);
DISPLAY 0.617021 (-5577 1183);
PAINT GREEN (-5577 1183);
FORCEPROP 2 LAST CDS_LIB mstr_standard
J 0
(-5575 1175);
PAINT MONO (-5575 1175);
DISPLAY INVISIBLE (-5575 1175);
FORCEPROP 1 LAST BODY_TYPE PLUMBING
J 0
(-5575 1125);
DISPLAY 1.595745 (-5575 1125);
PAINT GREEN (-5575 1125);
DISPLAY INVISIBLE (-5575 1125);
FORCEPROP 1 LAST HDL_TAP TRUE
J 0
(-5250 1050);
DISPLAY 1.595745 (-5250 1050);
PAINT GREEN (-5250 1050);
DISPLAY INVISIBLE (-5250 1050);
FORCEPROP 1 LAST PATH I15
J 0
(-5577 1175);
DISPLAY 0.872340 (-5577 1175);
PAINT GREEN (-5577 1175);
DISPLAY INVISIBLE (-5577 1175);
FORCEADD OFFPAGE..2
(-2000 825);
FORCEPROP 2 LAST $XR1 78 
J 0
(-1721 825);
DISPLAY 0.638298 (-1721 825);
PAINT MONO (-1721 825);
FORCEPROP 2 LAST $XR0 77 
J 0
(-1811 825);
DISPLAY 0.638298 (-1811 825);
PAINT MONO (-1811 825);
FORCEPROP 2 LAST CDS_LIB mstr_standard
J 0
(-2000 825);
PAINT MONO (-2000 825);
DISPLAY INVISIBLE (-2000 825);
FORCEPROP 1 LAST OFFPAGE TRUE
J 0
(-1675 700);
DISPLAY 1.170213 (-1675 700);
PAINT GREEN (-1675 700);
DISPLAY INVISIBLE (-1675 700);
FORCEPROP 1 LAST COMMENT_BODY TRUE
J 0
(-2045 730);
DISPLAY 1.170213 (-2045 730);
PAINT GREEN (-2045 730);
DISPLAY INVISIBLE (-2045 730);
FORCEPROP 2 LAST PATH I150
J 0
(-1825 900);
DISPLAY 1.021277 (-1825 900);
PAINT ORANGE (-1825 900);
DISPLAY INVISIBLE (-1825 900);
FORCEADD OFFPAGE..2
(-2000 925);
FORCEPROP 2 LAST $XR1 78 
J 0
(-1721 925);
DISPLAY 0.638298 (-1721 925);
PAINT MONO (-1721 925);
FORCEPROP 2 LAST $XR0 77 
J 0
(-1811 925);
DISPLAY 0.638298 (-1811 925);
PAINT MONO (-1811 925);
FORCEPROP 2 LAST CDS_LIB mstr_standard
J 0
(-2000 925);
PAINT MONO (-2000 925);
DISPLAY INVISIBLE (-2000 925);
FORCEPROP 1 LAST OFFPAGE TRUE
J 0
(-1675 800);
DISPLAY 1.170213 (-1675 800);
PAINT GREEN (-1675 800);
DISPLAY INVISIBLE (-1675 800);
FORCEPROP 1 LAST COMMENT_BODY TRUE
J 0
(-2045 830);
DISPLAY 1.170213 (-2045 830);
PAINT GREEN (-2045 830);
DISPLAY INVISIBLE (-2045 830);
FORCEPROP 2 LAST PATH I151
J 0
(-1825 1000);
DISPLAY 1.021277 (-1825 1000);
PAINT ORANGE (-1825 1000);
DISPLAY INVISIBLE (-1825 1000);
FORCEADD OFFPAGE..2
(-2000 1375);
FORCEPROP 2 LAST $XR1 78 
J 0
(-1721 1375);
DISPLAY 0.638298 (-1721 1375);
PAINT MONO (-1721 1375);
FORCEPROP 2 LAST $XR0 77 
J 0
(-1811 1375);
DISPLAY 0.638298 (-1811 1375);
PAINT MONO (-1811 1375);
FORCEPROP 2 LAST CDS_LIB mstr_standard
J 0
(-2000 1375);
PAINT MONO (-2000 1375);
DISPLAY INVISIBLE (-2000 1375);
FORCEPROP 1 LAST OFFPAGE TRUE
J 0
(-1675 1250);
DISPLAY 1.170213 (-1675 1250);
PAINT GREEN (-1675 1250);
DISPLAY INVISIBLE (-1675 1250);
FORCEPROP 1 LAST COMMENT_BODY TRUE
J 0
(-2045 1280);
DISPLAY 1.170213 (-2045 1280);
PAINT GREEN (-2045 1280);
DISPLAY INVISIBLE (-2045 1280);
FORCEPROP 2 LAST PATH I152
J 0
(-1825 1450);
DISPLAY 1.021277 (-1825 1450);
PAINT ORANGE (-1825 1450);
DISPLAY INVISIBLE (-1825 1450);
FORCEADD OFFPAGE..2
(-2000 1625);
FORCEPROP 2 LAST $XR1 78 
J 0
(-1721 1625);
DISPLAY 0.638298 (-1721 1625);
PAINT MONO (-1721 1625);
FORCEPROP 2 LAST $XR0 77 
J 0
(-1811 1625);
DISPLAY 0.638298 (-1811 1625);
PAINT MONO (-1811 1625);
FORCEPROP 2 LAST CDS_LIB mstr_standard
J 0
(-2000 1625);
PAINT MONO (-2000 1625);
DISPLAY INVISIBLE (-2000 1625);
FORCEPROP 1 LAST OFFPAGE TRUE
J 0
(-1675 1500);
DISPLAY 1.170213 (-1675 1500);
PAINT GREEN (-1675 1500);
DISPLAY INVISIBLE (-1675 1500);
FORCEPROP 1 LAST COMMENT_BODY TRUE
J 0
(-2045 1530);
DISPLAY 1.170213 (-2045 1530);
PAINT GREEN (-2045 1530);
DISPLAY INVISIBLE (-2045 1530);
FORCEPROP 2 LAST PATH I153
J 0
(-1825 1700);
DISPLAY 1.021277 (-1825 1700);
PAINT ORANGE (-1825 1700);
DISPLAY INVISIBLE (-1825 1700);
FORCEADD OFFPAGE..2
(-2000 1875);
FORCEPROP 2 LAST $XR1 78 
J 0
(-1721 1875);
DISPLAY 0.638298 (-1721 1875);
PAINT MONO (-1721 1875);
FORCEPROP 2 LAST $XR0 77 
J 0
(-1811 1875);
DISPLAY 0.638298 (-1811 1875);
PAINT MONO (-1811 1875);
FORCEPROP 2 LAST CDS_LIB mstr_standard
J 0
(-2000 1875);
PAINT MONO (-2000 1875);
DISPLAY INVISIBLE (-2000 1875);
FORCEPROP 1 LAST OFFPAGE TRUE
J 0
(-1675 1750);
DISPLAY 1.170213 (-1675 1750);
PAINT GREEN (-1675 1750);
DISPLAY INVISIBLE (-1675 1750);
FORCEPROP 1 LAST COMMENT_BODY TRUE
J 0
(-2045 1780);
DISPLAY 1.170213 (-2045 1780);
PAINT GREEN (-2045 1780);
DISPLAY INVISIBLE (-2045 1780);
FORCEPROP 2 LAST PATH I154
J 0
(-1825 1950);
DISPLAY 1.021277 (-1825 1950);
PAINT ORANGE (-1825 1950);
DISPLAY INVISIBLE (-1825 1950);
FORCEADD OFFPAGE..2
(-2000 2825);
FORCEPROP 2 LAST $XR1 78 
J 0
(-1721 2825);
DISPLAY 0.638298 (-1721 2825);
PAINT MONO (-1721 2825);
FORCEPROP 2 LAST $XR0 77 
J 0
(-1811 2825);
DISPLAY 0.638298 (-1811 2825);
PAINT MONO (-1811 2825);
FORCEPROP 2 LAST CDS_LIB mstr_standard
J 0
(-2000 2825);
PAINT MONO (-2000 2825);
DISPLAY INVISIBLE (-2000 2825);
FORCEPROP 1 LAST OFFPAGE TRUE
J 0
(-1675 2700);
DISPLAY 1.170213 (-1675 2700);
PAINT GREEN (-1675 2700);
DISPLAY INVISIBLE (-1675 2700);
FORCEPROP 1 LAST COMMENT_BODY TRUE
J 0
(-2045 2730);
DISPLAY 1.170213 (-2045 2730);
PAINT GREEN (-2045 2730);
DISPLAY INVISIBLE (-2045 2730);
FORCEPROP 2 LAST PATH I155
J 0
(-1825 2900);
DISPLAY 1.021277 (-1825 2900);
PAINT ORANGE (-1825 2900);
DISPLAY INVISIBLE (-1825 2900);
FORCEADD OFFPAGE..3
(-2000 3775);
FORCEPROP 2 LAST $XR1 78 
J 0
(-1696 3775);
DISPLAY 0.638298 (-1696 3775);
PAINT MONO (-1696 3775);
FORCEPROP 2 LAST $XR0 77 
J 0
(-1786 3775);
DISPLAY 0.638298 (-1786 3775);
PAINT MONO (-1786 3775);
FORCEPROP 2 LAST CDS_LIB mstr_standard
J 0
(-2000 3775);
PAINT MONO (-2000 3775);
DISPLAY INVISIBLE (-2000 3775);
FORCEPROP 1 LAST OFFPAGE TRUE
J 0
(-1675 3650);
DISPLAY 1.170213 (-1675 3650);
PAINT GREEN (-1675 3650);
DISPLAY INVISIBLE (-1675 3650);
FORCEPROP 1 LAST COMMENT_BODY TRUE
J 0
(-2050 3675);
DISPLAY 1.170213 (-2050 3675);
PAINT GREEN (-2050 3675);
DISPLAY INVISIBLE (-2050 3675);
FORCEPROP 2 LAST PATH I156
J 0
(-1800 3850);
DISPLAY 1.021277 (-1800 3850);
PAINT ORANGE (-1800 3850);
DISPLAY INVISIBLE (-1800 3850);
FORCEADD TAP..6
R 2
(-2850 4025);
FORCEPROP 3 LASTPIN (-2900 4025) SIG_NAME M_G_DQS_DP<4>
J 0
(-2890 4035);
DISPLAY 0.659574 (-2890 4035);
PAINT MONO (-2890 4035);
DISPLAY INVISIBLE (-2890 4035);
FORCEPROP 1 LASTPIN (-2900 4025) BN 4
J 2
(-2848 4033);
DISPLAY 0.617021 (-2848 4033);
PAINT GREEN (-2848 4033);
FORCEPROP 2 LAST CDS_LIB mstr_standard
J 0
(-2850 4025);
PAINT MONO (-2850 4025);
DISPLAY INVISIBLE (-2850 4025);
FORCEPROP 1 LAST BODY_TYPE PLUMBING
J 2
(-2850 3975);
DISPLAY 1.595745 (-2850 3975);
PAINT GREEN (-2850 3975);
DISPLAY INVISIBLE (-2850 3975);
FORCEPROP 1 LAST HDL_TAP TRUE
J 2
(-3175 3900);
DISPLAY 1.595745 (-3175 3900);
PAINT GREEN (-3175 3900);
DISPLAY INVISIBLE (-3175 3900);
FORCEPROP 1 LAST PATH I157
J 2
(-2848 4025);
DISPLAY 0.872340 (-2848 4025);
PAINT GREEN (-2848 4025);
DISPLAY INVISIBLE (-2848 4025);
FORCEADD TAP..6
R 2
(-2850 4125);
FORCEPROP 3 LASTPIN (-2900 4125) SIG_NAME M_G_DQS_DP<6>
J 0
(-2890 4135);
DISPLAY 0.659574 (-2890 4135);
PAINT MONO (-2890 4135);
DISPLAY INVISIBLE (-2890 4135);
FORCEPROP 1 LASTPIN (-2900 4125) BN 6
J 2
(-2848 4133);
DISPLAY 0.617021 (-2848 4133);
PAINT GREEN (-2848 4133);
FORCEPROP 2 LAST CDS_LIB mstr_standard
J 0
(-2850 4125);
PAINT MONO (-2850 4125);
DISPLAY INVISIBLE (-2850 4125);
FORCEPROP 1 LAST BODY_TYPE PLUMBING
J 2
(-2850 4075);
DISPLAY 1.595745 (-2850 4075);
PAINT GREEN (-2850 4075);
DISPLAY INVISIBLE (-2850 4075);
FORCEPROP 1 LAST HDL_TAP TRUE
J 2
(-3175 4000);
DISPLAY 1.595745 (-3175 4000);
PAINT GREEN (-3175 4000);
DISPLAY INVISIBLE (-3175 4000);
FORCEPROP 1 LAST PATH I158
J 2
(-2848 4125);
DISPLAY 0.872340 (-2848 4125);
PAINT GREEN (-2848 4125);
DISPLAY INVISIBLE (-2848 4125);
FORCEADD TAP..6
R 2
(-2850 4075);
FORCEPROP 3 LASTPIN (-2900 4075) SIG_NAME M_G_DQS_DP<5>
J 0
(-2890 4085);
DISPLAY 0.659574 (-2890 4085);
PAINT MONO (-2890 4085);
DISPLAY INVISIBLE (-2890 4085);
FORCEPROP 1 LASTPIN (-2900 4075) BN 5
J 2
(-2848 4083);
DISPLAY 0.617021 (-2848 4083);
PAINT GREEN (-2848 4083);
FORCEPROP 2 LAST CDS_LIB mstr_standard
J 0
(-2850 4075);
PAINT MONO (-2850 4075);
DISPLAY INVISIBLE (-2850 4075);
FORCEPROP 1 LAST BODY_TYPE PLUMBING
J 2
(-2850 4025);
DISPLAY 1.595745 (-2850 4025);
PAINT GREEN (-2850 4025);
DISPLAY INVISIBLE (-2850 4025);
FORCEPROP 1 LAST HDL_TAP TRUE
J 2
(-3175 3950);
DISPLAY 1.595745 (-3175 3950);
PAINT GREEN (-3175 3950);
DISPLAY INVISIBLE (-3175 3950);
FORCEPROP 1 LAST PATH I159
J 2
(-2848 4075);
DISPLAY 0.872340 (-2848 4075);
PAINT GREEN (-2848 4075);
DISPLAY INVISIBLE (-2848 4075);
FORCEADD TAP..6
(-5575 1275);
FORCEPROP 3 LASTPIN (-5525 1275) SIG_NAME M_G_ECC<4>
J 0
(-5515 1285);
DISPLAY 0.659574 (-5515 1285);
PAINT MONO (-5515 1285);
DISPLAY INVISIBLE (-5515 1285);
FORCEPROP 1 LASTPIN (-5525 1275) BN 4
J 0
(-5577 1283);
DISPLAY 0.617021 (-5577 1283);
PAINT GREEN (-5577 1283);
FORCEPROP 2 LAST CDS_LIB mstr_standard
J 0
(-5575 1275);
PAINT MONO (-5575 1275);
DISPLAY INVISIBLE (-5575 1275);
FORCEPROP 1 LAST BODY_TYPE PLUMBING
J 0
(-5575 1225);
DISPLAY 1.595745 (-5575 1225);
PAINT GREEN (-5575 1225);
DISPLAY INVISIBLE (-5575 1225);
FORCEPROP 1 LAST HDL_TAP TRUE
J 0
(-5250 1150);
DISPLAY 1.595745 (-5250 1150);
PAINT GREEN (-5250 1150);
DISPLAY INVISIBLE (-5250 1150);
FORCEPROP 1 LAST PATH I16
J 0
(-5577 1275);
DISPLAY 0.872340 (-5577 1275);
PAINT GREEN (-5577 1275);
DISPLAY INVISIBLE (-5577 1275);
FORCEADD TAP..6
R 2
(-2850 4175);
FORCEPROP 3 LASTPIN (-2900 4175) SIG_NAME M_G_DQS_DP<7>
J 0
(-2890 4185);
DISPLAY 0.659574 (-2890 4185);
PAINT MONO (-2890 4185);
DISPLAY INVISIBLE (-2890 4185);
FORCEPROP 1 LASTPIN (-2900 4175) BN 7
J 2
(-2848 4183);
DISPLAY 0.617021 (-2848 4183);
PAINT GREEN (-2848 4183);
FORCEPROP 2 LAST CDS_LIB mstr_standard
J 0
(-2850 4175);
PAINT MONO (-2850 4175);
DISPLAY INVISIBLE (-2850 4175);
FORCEPROP 1 LAST BODY_TYPE PLUMBING
J 2
(-2850 4125);
DISPLAY 1.595745 (-2850 4125);
PAINT GREEN (-2850 4125);
DISPLAY INVISIBLE (-2850 4125);
FORCEPROP 1 LAST HDL_TAP TRUE
J 2
(-3175 4050);
DISPLAY 1.595745 (-3175 4050);
PAINT GREEN (-3175 4050);
DISPLAY INVISIBLE (-3175 4050);
FORCEPROP 1 LAST PATH I160
J 2
(-2848 4175);
DISPLAY 0.872340 (-2848 4175);
PAINT GREEN (-2848 4175);
DISPLAY INVISIBLE (-2848 4175);
FORCEADD TAP..6
R 2
(-2850 4225);
FORCEPROP 3 LASTPIN (-2900 4225) SIG_NAME M_G_DQS_DP<8>
J 0
(-2890 4235);
DISPLAY 0.659574 (-2890 4235);
PAINT MONO (-2890 4235);
DISPLAY INVISIBLE (-2890 4235);
FORCEPROP 1 LASTPIN (-2900 4225) BN 8
J 2
(-2848 4233);
DISPLAY 0.617021 (-2848 4233);
PAINT GREEN (-2848 4233);
FORCEPROP 2 LAST CDS_LIB mstr_standard
J 0
(-2850 4225);
PAINT MONO (-2850 4225);
DISPLAY INVISIBLE (-2850 4225);
FORCEPROP 1 LAST BODY_TYPE PLUMBING
J 2
(-2850 4175);
DISPLAY 1.595745 (-2850 4175);
PAINT GREEN (-2850 4175);
DISPLAY INVISIBLE (-2850 4175);
FORCEPROP 1 LAST HDL_TAP TRUE
J 2
(-3175 4100);
DISPLAY 1.595745 (-3175 4100);
PAINT GREEN (-3175 4100);
DISPLAY INVISIBLE (-3175 4100);
FORCEPROP 1 LAST PATH I161
J 2
(-2848 4225);
DISPLAY 0.872340 (-2848 4225);
PAINT GREEN (-2848 4225);
DISPLAY INVISIBLE (-2848 4225);
FORCEADD TAP..6
R 2
(-2850 4275);
FORCEPROP 3 LASTPIN (-2900 4275) SIG_NAME M_G_DQS_DP<9>
J 0
(-2890 4285);
DISPLAY 0.659574 (-2890 4285);
PAINT MONO (-2890 4285);
DISPLAY INVISIBLE (-2890 4285);
FORCEPROP 1 LASTPIN (-2900 4275) BN 9
J 2
(-2848 4283);
DISPLAY 0.617021 (-2848 4283);
PAINT GREEN (-2848 4283);
FORCEPROP 2 LAST CDS_LIB mstr_standard
J 0
(-2850 4275);
PAINT MONO (-2850 4275);
DISPLAY INVISIBLE (-2850 4275);
FORCEPROP 1 LAST BODY_TYPE PLUMBING
J 2
(-2850 4225);
DISPLAY 1.595745 (-2850 4225);
PAINT GREEN (-2850 4225);
DISPLAY INVISIBLE (-2850 4225);
FORCEPROP 1 LAST HDL_TAP TRUE
J 2
(-3175 4150);
DISPLAY 1.595745 (-3175 4150);
PAINT GREEN (-3175 4150);
DISPLAY INVISIBLE (-3175 4150);
FORCEPROP 1 LAST PATH I162
J 2
(-2848 4275);
DISPLAY 0.872340 (-2848 4275);
PAINT GREEN (-2848 4275);
DISPLAY INVISIBLE (-2848 4275);
FORCEADD TAP..6
R 2
(-2850 4325);
FORCEPROP 3 LASTPIN (-2900 4325) SIG_NAME M_G_DQS_DP<10>
J 0
(-2890 4335);
DISPLAY 0.659574 (-2890 4335);
PAINT MONO (-2890 4335);
DISPLAY INVISIBLE (-2890 4335);
FORCEPROP 1 LASTPIN (-2900 4325) BN 10
J 2
(-2848 4333);
DISPLAY 0.617021 (-2848 4333);
PAINT GREEN (-2848 4333);
FORCEPROP 2 LAST CDS_LIB mstr_standard
J 0
(-2850 4325);
PAINT MONO (-2850 4325);
DISPLAY INVISIBLE (-2850 4325);
FORCEPROP 1 LAST BODY_TYPE PLUMBING
J 2
(-2850 4275);
DISPLAY 1.595745 (-2850 4275);
PAINT GREEN (-2850 4275);
DISPLAY INVISIBLE (-2850 4275);
FORCEPROP 1 LAST HDL_TAP TRUE
J 2
(-3175 4200);
DISPLAY 1.595745 (-3175 4200);
PAINT GREEN (-3175 4200);
DISPLAY INVISIBLE (-3175 4200);
FORCEPROP 1 LAST PATH I163
J 2
(-2848 4325);
DISPLAY 0.872340 (-2848 4325);
PAINT GREEN (-2848 4325);
DISPLAY INVISIBLE (-2848 4325);
FORCEADD TAP..6
R 2
(-2850 4375);
FORCEPROP 3 LASTPIN (-2900 4375) SIG_NAME M_G_DQS_DP<11>
J 0
(-2890 4385);
DISPLAY 0.659574 (-2890 4385);
PAINT MONO (-2890 4385);
DISPLAY INVISIBLE (-2890 4385);
FORCEPROP 1 LASTPIN (-2900 4375) BN 11
J 2
(-2848 4383);
DISPLAY 0.617021 (-2848 4383);
PAINT GREEN (-2848 4383);
FORCEPROP 2 LAST CDS_LIB mstr_standard
J 0
(-2850 4375);
PAINT MONO (-2850 4375);
DISPLAY INVISIBLE (-2850 4375);
FORCEPROP 1 LAST BODY_TYPE PLUMBING
J 2
(-2850 4325);
DISPLAY 1.595745 (-2850 4325);
PAINT GREEN (-2850 4325);
DISPLAY INVISIBLE (-2850 4325);
FORCEPROP 1 LAST HDL_TAP TRUE
J 2
(-3175 4250);
DISPLAY 1.595745 (-3175 4250);
PAINT GREEN (-3175 4250);
DISPLAY INVISIBLE (-3175 4250);
FORCEPROP 1 LAST PATH I164
J 2
(-2848 4375);
DISPLAY 0.872340 (-2848 4375);
PAINT GREEN (-2848 4375);
DISPLAY INVISIBLE (-2848 4375);
FORCEADD TAP..6
R 2
(-2850 4525);
FORCEPROP 3 LASTPIN (-2900 4525) SIG_NAME M_G_DQS_DP<14>
J 0
(-2890 4535);
DISPLAY 0.659574 (-2890 4535);
PAINT MONO (-2890 4535);
DISPLAY INVISIBLE (-2890 4535);
FORCEPROP 1 LASTPIN (-2900 4525) BN 14
J 2
(-2848 4533);
DISPLAY 0.617021 (-2848 4533);
PAINT GREEN (-2848 4533);
FORCEPROP 2 LAST CDS_LIB mstr_standard
J 0
(-2850 4525);
PAINT MONO (-2850 4525);
DISPLAY INVISIBLE (-2850 4525);
FORCEPROP 1 LAST BODY_TYPE PLUMBING
J 2
(-2850 4475);
DISPLAY 1.595745 (-2850 4475);
PAINT GREEN (-2850 4475);
DISPLAY INVISIBLE (-2850 4475);
FORCEPROP 1 LAST HDL_TAP TRUE
J 2
(-3175 4400);
DISPLAY 1.595745 (-3175 4400);
PAINT GREEN (-3175 4400);
DISPLAY INVISIBLE (-3175 4400);
FORCEPROP 1 LAST PATH I165
J 2
(-2848 4525);
DISPLAY 0.872340 (-2848 4525);
PAINT GREEN (-2848 4525);
DISPLAY INVISIBLE (-2848 4525);
FORCEADD TAP..6
R 2
(-2850 4475);
FORCEPROP 3 LASTPIN (-2900 4475) SIG_NAME M_G_DQS_DP<13>
J 0
(-2890 4485);
DISPLAY 0.659574 (-2890 4485);
PAINT MONO (-2890 4485);
DISPLAY INVISIBLE (-2890 4485);
FORCEPROP 1 LASTPIN (-2900 4475) BN 13
J 2
(-2848 4483);
DISPLAY 0.617021 (-2848 4483);
PAINT GREEN (-2848 4483);
FORCEPROP 2 LAST CDS_LIB mstr_standard
J 0
(-2850 4475);
PAINT MONO (-2850 4475);
DISPLAY INVISIBLE (-2850 4475);
FORCEPROP 1 LAST BODY_TYPE PLUMBING
J 2
(-2850 4425);
DISPLAY 1.595745 (-2850 4425);
PAINT GREEN (-2850 4425);
DISPLAY INVISIBLE (-2850 4425);
FORCEPROP 1 LAST HDL_TAP TRUE
J 2
(-3175 4350);
DISPLAY 1.595745 (-3175 4350);
PAINT GREEN (-3175 4350);
DISPLAY INVISIBLE (-3175 4350);
FORCEPROP 1 LAST PATH I166
J 2
(-2848 4475);
DISPLAY 0.872340 (-2848 4475);
PAINT GREEN (-2848 4475);
DISPLAY INVISIBLE (-2848 4475);
FORCEADD TAP..6
R 2
(-2850 4425);
FORCEPROP 3 LASTPIN (-2900 4425) SIG_NAME M_G_DQS_DP<12>
J 0
(-2890 4435);
DISPLAY 0.659574 (-2890 4435);
PAINT MONO (-2890 4435);
DISPLAY INVISIBLE (-2890 4435);
FORCEPROP 1 LASTPIN (-2900 4425) BN 12
J 2
(-2848 4433);
DISPLAY 0.617021 (-2848 4433);
PAINT GREEN (-2848 4433);
FORCEPROP 2 LAST CDS_LIB mstr_standard
J 0
(-2850 4425);
PAINT MONO (-2850 4425);
DISPLAY INVISIBLE (-2850 4425);
FORCEPROP 1 LAST BODY_TYPE PLUMBING
J 2
(-2850 4375);
DISPLAY 1.595745 (-2850 4375);
PAINT GREEN (-2850 4375);
DISPLAY INVISIBLE (-2850 4375);
FORCEPROP 1 LAST HDL_TAP TRUE
J 2
(-3175 4300);
DISPLAY 1.595745 (-3175 4300);
PAINT GREEN (-3175 4300);
DISPLAY INVISIBLE (-3175 4300);
FORCEPROP 1 LAST PATH I167
J 2
(-2848 4425);
DISPLAY 0.872340 (-2848 4425);
PAINT GREEN (-2848 4425);
DISPLAY INVISIBLE (-2848 4425);
FORCEADD TAP..6
R 2
(-2850 4575);
FORCEPROP 3 LASTPIN (-2900 4575) SIG_NAME M_G_DQS_DP<15>
J 0
(-2890 4585);
DISPLAY 0.659574 (-2890 4585);
PAINT MONO (-2890 4585);
DISPLAY INVISIBLE (-2890 4585);
FORCEPROP 1 LASTPIN (-2900 4575) BN 15
J 2
(-2848 4583);
DISPLAY 0.617021 (-2848 4583);
PAINT GREEN (-2848 4583);
FORCEPROP 2 LAST CDS_LIB mstr_standard
J 0
(-2850 4575);
PAINT MONO (-2850 4575);
DISPLAY INVISIBLE (-2850 4575);
FORCEPROP 1 LAST BODY_TYPE PLUMBING
J 2
(-2850 4525);
DISPLAY 1.595745 (-2850 4525);
PAINT GREEN (-2850 4525);
DISPLAY INVISIBLE (-2850 4525);
FORCEPROP 1 LAST HDL_TAP TRUE
J 2
(-3175 4450);
DISPLAY 1.595745 (-3175 4450);
PAINT GREEN (-3175 4450);
DISPLAY INVISIBLE (-3175 4450);
FORCEPROP 1 LAST PATH I168
J 2
(-2848 4575);
DISPLAY 0.872340 (-2848 4575);
PAINT GREEN (-2848 4575);
DISPLAY INVISIBLE (-2848 4575);
FORCEADD TAP..6
R 2
(-2850 4625);
FORCEPROP 3 LASTPIN (-2900 4625) SIG_NAME M_G_DQS_DP<16>
J 0
(-2890 4635);
DISPLAY 0.659574 (-2890 4635);
PAINT MONO (-2890 4635);
DISPLAY INVISIBLE (-2890 4635);
FORCEPROP 1 LASTPIN (-2900 4625) BN 16
J 2
(-2848 4633);
DISPLAY 0.617021 (-2848 4633);
PAINT GREEN (-2848 4633);
FORCEPROP 2 LAST CDS_LIB mstr_standard
J 0
(-2850 4625);
PAINT MONO (-2850 4625);
DISPLAY INVISIBLE (-2850 4625);
FORCEPROP 1 LAST BODY_TYPE PLUMBING
J 2
(-2850 4575);
DISPLAY 1.595745 (-2850 4575);
PAINT GREEN (-2850 4575);
DISPLAY INVISIBLE (-2850 4575);
FORCEPROP 1 LAST HDL_TAP TRUE
J 2
(-3175 4500);
DISPLAY 1.595745 (-3175 4500);
PAINT GREEN (-3175 4500);
DISPLAY INVISIBLE (-3175 4500);
FORCEPROP 1 LAST PATH I169
J 2
(-2848 4625);
DISPLAY 0.872340 (-2848 4625);
PAINT GREEN (-2848 4625);
DISPLAY INVISIBLE (-2848 4625);
FORCEADD TAP..6
(-5575 1225);
FORCEPROP 3 LASTPIN (-5525 1225) SIG_NAME M_G_ECC<3>
J 0
(-5515 1235);
DISPLAY 0.659574 (-5515 1235);
PAINT MONO (-5515 1235);
DISPLAY INVISIBLE (-5515 1235);
FORCEPROP 1 LASTPIN (-5525 1225) BN 3
J 0
(-5577 1233);
DISPLAY 0.617021 (-5577 1233);
PAINT GREEN (-5577 1233);
FORCEPROP 2 LAST CDS_LIB mstr_standard
J 0
(-5575 1225);
PAINT MONO (-5575 1225);
DISPLAY INVISIBLE (-5575 1225);
FORCEPROP 1 LAST BODY_TYPE PLUMBING
J 0
(-5575 1175);
DISPLAY 1.595745 (-5575 1175);
PAINT GREEN (-5575 1175);
DISPLAY INVISIBLE (-5575 1175);
FORCEPROP 1 LAST HDL_TAP TRUE
J 0
(-5250 1100);
DISPLAY 1.595745 (-5250 1100);
PAINT GREEN (-5250 1100);
DISPLAY INVISIBLE (-5250 1100);
FORCEPROP 1 LAST PATH I17
J 0
(-5577 1225);
DISPLAY 0.872340 (-5577 1225);
PAINT GREEN (-5577 1225);
DISPLAY INVISIBLE (-5577 1225);
FORCEADD TAP..6
R 2
(-2850 4675);
FORCEPROP 3 LASTPIN (-2900 4675) SIG_NAME M_G_DQS_DP<17>
J 0
(-2890 4685);
DISPLAY 0.659574 (-2890 4685);
PAINT MONO (-2890 4685);
DISPLAY INVISIBLE (-2890 4685);
FORCEPROP 1 LASTPIN (-2900 4675) BN 17
J 2
(-2848 4683);
DISPLAY 0.617021 (-2848 4683);
PAINT GREEN (-2848 4683);
FORCEPROP 2 LAST CDS_LIB mstr_standard
J 2
(-2850 4675);
PAINT MONO (-2850 4675);
DISPLAY INVISIBLE (-2850 4675);
FORCEPROP 1 LAST BODY_TYPE PLUMBING
J 2
(-2850 4625);
DISPLAY 1.595745 (-2850 4625);
PAINT GREEN (-2850 4625);
DISPLAY INVISIBLE (-2850 4625);
FORCEPROP 1 LAST HDL_TAP TRUE
J 2
(-3175 4550);
DISPLAY 1.595745 (-3175 4550);
PAINT GREEN (-3175 4550);
DISPLAY INVISIBLE (-3175 4550);
FORCEPROP 1 LAST PATH I170
J 2
(-2848 4675);
DISPLAY 0.872340 (-2848 4675);
PAINT GREEN (-2848 4675);
DISPLAY INVISIBLE (-2848 4675);
FORCEADD OFFPAGE..3
(-2000 4750);
FORCEPROP 2 LAST $XR1 78 
J 0
(-1696 4750);
DISPLAY 0.638298 (-1696 4750);
PAINT MONO (-1696 4750);
FORCEPROP 2 LAST $XR0 77 
J 0
(-1786 4750);
DISPLAY 0.638298 (-1786 4750);
PAINT MONO (-1786 4750);
FORCEPROP 2 LAST CDS_LIB mstr_standard
J 0
(-2000 4750);
PAINT MONO (-2000 4750);
DISPLAY INVISIBLE (-2000 4750);
FORCEPROP 1 LAST OFFPAGE TRUE
J 0
(-1675 4625);
DISPLAY 1.170213 (-1675 4625);
PAINT GREEN (-1675 4625);
DISPLAY INVISIBLE (-1675 4625);
FORCEPROP 1 LAST COMMENT_BODY TRUE
J 0
(-2050 4650);
DISPLAY 1.170213 (-2050 4650);
PAINT GREEN (-2050 4650);
DISPLAY INVISIBLE (-2050 4650);
FORCEPROP 2 LAST PATH I171
J 0
(-1800 4825);
DISPLAY 1.021277 (-1800 4825);
PAINT ORANGE (-1800 4825);
DISPLAY INVISIBLE (-1800 4825);
FORCEADD SKX_EXT_B..3
(-4175 2575);
FORCEPROP 1 LAST LOCATION U2D1
J 0
(-4975 4925);
DISPLAY 0.617021 (-4975 4925);
PAINT AQUA (-4975 4925);
FORCEPROP 1 LAST PART_NUMBER TBD
J 0
(-4975 325);
DISPLAY 0.617021 (-4975 325);
PAINT BLUE (-4975 325);
FORCEPROP 1 LAST MATERIAL IC
J 0
(-4975 4875);
DISPLAY 0.617021 (-4975 4875);
PAINT SKYBLUE (-4975 4875);
FORCEPROP 2 LASTPIN (-3325 525) $PN D53
J 0
(-3315 535);
DISPLAY 0.617021 (-3315 535);
PAINT ORANGE (-3315 535);
FORCEPROP 2 LASTPIN (-3325 1575) $PN G48
J 0
(-3315 1585);
DISPLAY 0.617021 (-3315 1585);
PAINT ORANGE (-3315 1585);
FORCEPROP 2 LASTPIN (-3325 1525) $PN G50
J 0
(-3315 1535);
DISPLAY 0.617021 (-3315 1535);
PAINT ORANGE (-3315 1535);
FORCEPROP 2 LASTPIN (-3325 1475) $PN C48
J 0
(-3315 1485);
DISPLAY 0.617021 (-3315 1485);
PAINT ORANGE (-3315 1485);
FORCEPROP 2 LASTPIN (-3325 1425) $PN C50
J 0
(-3315 1435);
DISPLAY 0.617021 (-3315 1435);
PAINT ORANGE (-3315 1435);
FORCEPROP 2 LASTPIN (-3325 2775) $PN K47
J 0
(-3315 2785);
DISPLAY 0.617021 (-3315 2785);
PAINT ORANGE (-3315 2785);
FORCEPROP 2 LASTPIN (-3325 2725) $PN D51
J 0
(-3315 2735);
DISPLAY 0.617021 (-3315 2735);
PAINT ORANGE (-3315 2735);
FORCEPROP 2 LASTPIN (-3325 2675) $PN K49
J 0
(-3315 2685);
DISPLAY 0.617021 (-3315 2685);
PAINT ORANGE (-3315 2685);
FORCEPROP 2 LASTPIN (-3325 2625) $PN F51
J 0
(-3315 2635);
DISPLAY 0.617021 (-3315 2635);
PAINT ORANGE (-3315 2635);
FORCEPROP 2 LASTPIN (-3325 2575) $PN J48
J 0
(-3315 2585);
DISPLAY 0.617021 (-3315 2585);
PAINT ORANGE (-3315 2585);
FORCEPROP 2 LASTPIN (-3325 2525) $PN J64
J 0
(-3315 2535);
DISPLAY 0.617021 (-3315 2535);
PAINT ORANGE (-3315 2535);
FORCEPROP 2 LASTPIN (-3325 2475) $PN G62
J 0
(-3315 2485);
DISPLAY 0.617021 (-3315 2485);
PAINT ORANGE (-3315 2485);
FORCEPROP 2 LASTPIN (-3325 2425) $PN J54
J 0
(-3315 2435);
DISPLAY 0.617021 (-3315 2435);
PAINT ORANGE (-3315 2435);
FORCEPROP 2 LASTPIN (-3325 2375) $PN F61
J 0
(-3315 2385);
DISPLAY 0.617021 (-3315 2385);
PAINT ORANGE (-3315 2385);
FORCEPROP 2 LASTPIN (-3325 2325) $PN C60
J 0
(-3315 2335);
DISPLAY 0.617021 (-3315 2335);
PAINT ORANGE (-3315 2335);
FORCEPROP 2 LASTPIN (-3325 2275) $PN G60
J 0
(-3315 2285);
DISPLAY 0.617021 (-3315 2285);
PAINT ORANGE (-3315 2285);
FORCEPROP 2 LASTPIN (-3325 2225) $PN D59
J 0
(-3315 2235);
DISPLAY 0.617021 (-3315 2235);
PAINT ORANGE (-3315 2235);
FORCEPROP 2 LASTPIN (-3325 2175) $PN F59
J 0
(-3315 2185);
DISPLAY 0.617021 (-3315 2185);
PAINT ORANGE (-3315 2185);
FORCEPROP 2 LASTPIN (-3325 2125) $PN G58
J 0
(-3315 2135);
DISPLAY 0.617021 (-3315 2135);
PAINT ORANGE (-3315 2135);
FORCEPROP 2 LASTPIN (-3325 2075) $PN C58
J 0
(-3315 2085);
DISPLAY 0.617021 (-3315 2085);
PAINT ORANGE (-3315 2085);
FORCEPROP 2 LASTPIN (-3325 2025) $PN D57
J 0
(-3315 2035);
DISPLAY 0.617021 (-3315 2035);
PAINT ORANGE (-3315 2035);
FORCEPROP 2 LASTPIN (-3325 1975) $PN F57
J 0
(-3315 1985);
DISPLAY 0.617021 (-3315 1985);
PAINT ORANGE (-3315 1985);
FORCEPROP 2 LASTPIN (-3325 1925) $PN F53
J 0
(-3315 1935);
DISPLAY 0.617021 (-3315 1935);
PAINT ORANGE (-3315 1935);
FORCEPROP 2 LASTPIN (-5025 1425) $PN AG66
J 2
(-5035 1435);
DISPLAY 0.617021 (-5035 1435);
PAINT ORANGE (-5035 1435);
FORCEPROP 2 LASTPIN (-5025 1375) $PN AC66
J 2
(-5035 1385);
DISPLAY 0.617021 (-5035 1385);
PAINT ORANGE (-5035 1385);
FORCEPROP 2 LASTPIN (-5025 1325) $PN AF69
J 2
(-5035 1335);
DISPLAY 0.617021 (-5035 1335);
PAINT ORANGE (-5035 1335);
FORCEPROP 2 LASTPIN (-5025 1275) $PN AD69
J 2
(-5035 1285);
DISPLAY 0.617021 (-5035 1285);
PAINT ORANGE (-5035 1285);
FORCEPROP 2 LASTPIN (-5025 1225) $PN AF65
J 2
(-5035 1235);
DISPLAY 0.617021 (-5035 1235);
PAINT ORANGE (-5035 1235);
FORCEPROP 2 LASTPIN (-5025 1175) $PN AD65
J 2
(-5035 1185);
DISPLAY 0.617021 (-5035 1185);
PAINT ORANGE (-5035 1185);
FORCEPROP 2 LASTPIN (-5025 1125) $PN AG68
J 2
(-5035 1135);
DISPLAY 0.617021 (-5035 1135);
PAINT ORANGE (-5035 1135);
FORCEPROP 2 LASTPIN (-5025 1075) $PN AC68
J 2
(-5035 1085);
DISPLAY 0.617021 (-5035 1085);
PAINT ORANGE (-5035 1085);
FORCEPROP 2 LASTPIN (-3325 4675) $PN AD67
J 0
(-3315 4685);
DISPLAY 0.617021 (-3315 4685);
PAINT ORANGE (-3315 4685);
FORCEPROP 2 LASTPIN (-3325 4625) $PN L24
J 0
(-3315 4635);
DISPLAY 0.617021 (-3315 4635);
PAINT ORANGE (-3315 4635);
FORCEPROP 2 LASTPIN (-3325 4575) $PN L30
J 0
(-3315 4585);
DISPLAY 0.617021 (-3315 4585);
PAINT ORANGE (-3315 4585);
FORCEPROP 2 LASTPIN (-3325 4525) $PN L36
J 0
(-3315 4535);
DISPLAY 0.617021 (-3315 4535);
PAINT ORANGE (-3315 4535);
FORCEPROP 2 LASTPIN (-3325 4475) $PN C40
J 0
(-3315 4485);
DISPLAY 0.617021 (-3315 4485);
PAINT ORANGE (-3315 4485);
FORCEPROP 2 LASTPIN (-3325 4425) $PN M75
J 0
(-3315 4435);
DISPLAY 0.617021 (-3315 4435);
PAINT ORANGE (-3315 4435);
FORCEPROP 2 LASTPIN (-3325 4375) $PN T81
J 0
(-3315 4385);
DISPLAY 0.617021 (-3315 4385);
PAINT ORANGE (-3315 4385);
FORCEPROP 2 LASTPIN (-3325 4325) $PN V85
J 0
(-3315 4335);
DISPLAY 0.617021 (-3315 4335);
PAINT ORANGE (-3315 4335);
FORCEPROP 2 LASTPIN (-3325 4275) $PN AM85
J 0
(-3315 4285);
DISPLAY 0.617021 (-3315 4285);
PAINT ORANGE (-3315 4285);
FORCEPROP 2 LASTPIN (-3325 4225) $PN AF67
J 0
(-3315 4235);
DISPLAY 0.617021 (-3315 4235);
PAINT ORANGE (-3315 4235);
FORCEPROP 2 LASTPIN (-3325 4175) $PN R24
J 0
(-3315 4185);
DISPLAY 0.617021 (-3315 4185);
PAINT ORANGE (-3315 4185);
FORCEPROP 2 LASTPIN (-3325 4125) $PN N30
J 0
(-3315 4135);
DISPLAY 0.617021 (-3315 4135);
PAINT ORANGE (-3315 4135);
FORCEPROP 2 LASTPIN (-3325 4075) $PN N36
J 0
(-3315 4085);
DISPLAY 0.617021 (-3315 4085);
PAINT ORANGE (-3315 4085);
FORCEPROP 2 LASTPIN (-3325 4025) $PN E40
J 0
(-3315 4035);
DISPLAY 0.617021 (-3315 4035);
PAINT ORANGE (-3315 4035);
FORCEPROP 2 LASTPIN (-3325 3975) $PN P75
J 0
(-3315 3985);
DISPLAY 0.617021 (-3315 3985);
PAINT ORANGE (-3315 3985);
FORCEPROP 2 LASTPIN (-3325 3925) $PN R80
J 0
(-3315 3935);
DISPLAY 0.617021 (-3315 3935);
PAINT ORANGE (-3315 3935);
FORCEPROP 2 LASTPIN (-3325 3875) $PN P85
J 0
(-3315 3885);
DISPLAY 0.617021 (-3315 3885);
PAINT ORANGE (-3315 3885);
FORCEPROP 2 LASTPIN (-3325 3825) $PN AH85
J 0
(-3315 3835);
DISPLAY 0.617021 (-3315 3835);
PAINT ORANGE (-3315 3835);
FORCEPROP 2 LASTPIN (-3325 3725) $PN AB67
J 0
(-3315 3735);
DISPLAY 0.617021 (-3315 3735);
PAINT ORANGE (-3315 3735);
FORCEPROP 2 LASTPIN (-3325 3675) $PN J24
J 0
(-3315 3685);
DISPLAY 0.617021 (-3315 3685);
PAINT ORANGE (-3315 3685);
FORCEPROP 2 LASTPIN (-3325 3625) $PN J30
J 0
(-3315 3635);
DISPLAY 0.617021 (-3315 3635);
PAINT ORANGE (-3315 3635);
FORCEPROP 2 LASTPIN (-3325 3575) $PN J36
J 0
(-3315 3585);
DISPLAY 0.617021 (-3315 3585);
PAINT ORANGE (-3315 3585);
FORCEPROP 2 LASTPIN (-3325 3525) $PN A40
J 0
(-3315 3535);
DISPLAY 0.617021 (-3315 3535);
PAINT ORANGE (-3315 3535);
FORCEPROP 2 LASTPIN (-3325 3475) $PN K75
J 0
(-3315 3485);
DISPLAY 0.617021 (-3315 3485);
PAINT ORANGE (-3315 3485);
FORCEPROP 2 LASTPIN (-3325 3425) $PN U82
J 0
(-3315 3435);
DISPLAY 0.617021 (-3315 3435);
PAINT ORANGE (-3315 3435);
FORCEPROP 2 LASTPIN (-3325 3375) $PN U84
J 0
(-3315 3385);
DISPLAY 0.617021 (-3315 3385);
PAINT ORANGE (-3315 3385);
FORCEPROP 2 LASTPIN (-3325 3325) $PN AL84
J 0
(-3315 3335);
DISPLAY 0.617021 (-3315 3335);
PAINT ORANGE (-3315 3335);
FORCEPROP 2 LASTPIN (-3325 3275) $PN AH67
J 0
(-3315 3285);
DISPLAY 0.617021 (-3315 3285);
PAINT ORANGE (-3315 3285);
FORCEPROP 2 LASTPIN (-3325 3225) $PN N24
J 0
(-3315 3235);
DISPLAY 0.617021 (-3315 3235);
PAINT ORANGE (-3315 3235);
FORCEPROP 2 LASTPIN (-3325 3175) $PN R30
J 0
(-3315 3185);
DISPLAY 0.617021 (-3315 3185);
PAINT ORANGE (-3315 3185);
FORCEPROP 2 LASTPIN (-3325 3125) $PN R36
J 0
(-3315 3135);
DISPLAY 0.617021 (-3315 3135);
PAINT ORANGE (-3315 3135);
FORCEPROP 2 LASTPIN (-3325 3075) $PN G40
J 0
(-3315 3085);
DISPLAY 0.617021 (-3315 3085);
PAINT ORANGE (-3315 3085);
FORCEPROP 2 LASTPIN (-3325 3025) $PN T75
J 0
(-3315 3035);
DISPLAY 0.617021 (-3315 3035);
PAINT ORANGE (-3315 3035);
FORCEPROP 2 LASTPIN (-3325 2975) $PN P79
J 0
(-3315 2985);
DISPLAY 0.617021 (-3315 2985);
PAINT ORANGE (-3315 2985);
FORCEPROP 2 LASTPIN (-3325 2925) $PN R84
J 0
(-3315 2935);
DISPLAY 0.617021 (-3315 2935);
PAINT ORANGE (-3315 2935);
FORCEPROP 2 LASTPIN (-3325 2875) $PN AJ84
J 0
(-3315 2885);
DISPLAY 0.617021 (-3315 2885);
PAINT ORANGE (-3315 2885);
FORCEPROP 2 LASTPIN (-5025 4675) $PN K23
J 2
(-5035 4685);
DISPLAY 0.617021 (-5035 4685);
PAINT ORANGE (-5035 4685);
FORCEPROP 2 LASTPIN (-5025 4625) $PN H23
J 2
(-5035 4635);
DISPLAY 0.617021 (-5035 4635);
PAINT ORANGE (-5035 4635);
FORCEPROP 2 LASTPIN (-5025 4575) $PN N26
J 2
(-5035 4585);
DISPLAY 0.617021 (-5035 4585);
PAINT ORANGE (-5035 4585);
FORCEPROP 2 LASTPIN (-5025 4525) $PN L26
J 2
(-5035 4535);
DISPLAY 0.617021 (-5035 4535);
PAINT ORANGE (-5035 4535);
FORCEPROP 2 LASTPIN (-5025 4475) $PN T23
J 2
(-5035 4485);
DISPLAY 0.617021 (-5035 4485);
PAINT ORANGE (-5035 4485);
FORCEPROP 2 LASTPIN (-5025 4425) $PN P23
J 2
(-5035 4435);
DISPLAY 0.617021 (-5035 4435);
PAINT ORANGE (-5035 4435);
FORCEPROP 2 LASTPIN (-5025 4375) $PN P25
J 2
(-5035 4385);
DISPLAY 0.617021 (-5035 4385);
PAINT ORANGE (-5035 4385);
FORCEPROP 2 LASTPIN (-5025 4325) $PN K25
J 2
(-5035 4335);
DISPLAY 0.617021 (-5035 4335);
PAINT ORANGE (-5035 4335);
FORCEPROP 2 LASTPIN (-5025 4275) $PN P29
J 2
(-5035 4285);
DISPLAY 0.617021 (-5035 4285);
PAINT ORANGE (-5035 4285);
FORCEPROP 2 LASTPIN (-5025 4225) $PN K29
J 2
(-5035 4235);
DISPLAY 0.617021 (-5035 4235);
PAINT ORANGE (-5035 4235);
FORCEPROP 2 LASTPIN (-5025 4175) $PN N32
J 2
(-5035 4185);
DISPLAY 0.617021 (-5035 4185);
PAINT ORANGE (-5035 4185);
FORCEPROP 2 LASTPIN (-5025 4125) $PN L32
J 2
(-5035 4135);
DISPLAY 0.617021 (-5035 4135);
PAINT ORANGE (-5035 4135);
FORCEPROP 2 LASTPIN (-5025 4075) $PN N28
J 2
(-5035 4085);
DISPLAY 0.617021 (-5035 4085);
PAINT ORANGE (-5035 4085);
FORCEPROP 2 LASTPIN (-5025 4025) $PN L28
J 2
(-5035 4035);
DISPLAY 0.617021 (-5035 4035);
PAINT ORANGE (-5035 4035);
FORCEPROP 2 LASTPIN (-5025 3975) $PN P31
J 2
(-5035 3985);
DISPLAY 0.617021 (-5035 3985);
PAINT ORANGE (-5035 3985);
FORCEPROP 2 LASTPIN (-5025 3925) $PN K31
J 2
(-5035 3935);
DISPLAY 0.617021 (-5035 3935);
PAINT ORANGE (-5035 3935);
FORCEPROP 2 LASTPIN (-5025 3875) $PN P35
J 2
(-5035 3885);
DISPLAY 0.617021 (-5035 3885);
PAINT ORANGE (-5035 3885);
FORCEPROP 2 LASTPIN (-5025 3825) $PN K35
J 2
(-5035 3835);
DISPLAY 0.617021 (-5035 3835);
PAINT ORANGE (-5035 3835);
FORCEPROP 2 LASTPIN (-5025 3775) $PN N38
J 2
(-5035 3785);
DISPLAY 0.617021 (-5035 3785);
PAINT ORANGE (-5035 3785);
FORCEPROP 2 LASTPIN (-5025 3725) $PN L38
J 2
(-5035 3735);
DISPLAY 0.617021 (-5035 3735);
PAINT ORANGE (-5035 3735);
FORCEPROP 2 LASTPIN (-5025 3675) $PN N34
J 2
(-5035 3685);
DISPLAY 0.617021 (-5035 3685);
PAINT ORANGE (-5035 3685);
FORCEPROP 2 LASTPIN (-5025 3625) $PN L34
J 2
(-5035 3635);
DISPLAY 0.617021 (-5035 3635);
PAINT ORANGE (-5035 3635);
FORCEPROP 2 LASTPIN (-5025 3575) $PN P37
J 2
(-5035 3585);
DISPLAY 0.617021 (-5035 3585);
PAINT ORANGE (-5035 3585);
FORCEPROP 2 LASTPIN (-5025 3525) $PN K37
J 2
(-5035 3535);
DISPLAY 0.617021 (-5035 3535);
PAINT ORANGE (-5035 3535);
FORCEPROP 2 LASTPIN (-5025 3475) $PN F39
J 2
(-5035 3485);
DISPLAY 0.617021 (-5035 3485);
PAINT ORANGE (-5035 3485);
FORCEPROP 2 LASTPIN (-5025 3425) $PN B39
J 2
(-5035 3435);
DISPLAY 0.617021 (-5035 3435);
PAINT ORANGE (-5035 3435);
FORCEPROP 2 LASTPIN (-5025 3375) $PN F41
J 2
(-5035 3385);
DISPLAY 0.617021 (-5035 3385);
PAINT ORANGE (-5035 3385);
FORCEPROP 2 LASTPIN (-5025 3325) $PN E42
J 2
(-5035 3335);
DISPLAY 0.617021 (-5035 3335);
PAINT ORANGE (-5035 3335);
FORCEPROP 2 LASTPIN (-5025 3275) $PN E38
J 2
(-5035 3285);
DISPLAY 0.617021 (-5035 3285);
PAINT ORANGE (-5035 3285);
FORCEPROP 2 LASTPIN (-5025 3225) $PN C38
J 2
(-5035 3235);
DISPLAY 0.617021 (-5035 3235);
PAINT ORANGE (-5035 3235);
FORCEPROP 2 LASTPIN (-5025 3175) $PN B41
J 2
(-5035 3185);
DISPLAY 0.617021 (-5035 3185);
PAINT ORANGE (-5035 3185);
FORCEPROP 2 LASTPIN (-5025 3125) $PN C42
J 2
(-5035 3135);
DISPLAY 0.617021 (-5035 3135);
PAINT ORANGE (-5035 3135);
FORCEPROP 2 LASTPIN (-5025 3075) $PN R74
J 2
(-5035 3085);
DISPLAY 0.617021 (-5035 3085);
PAINT ORANGE (-5035 3085);
FORCEPROP 2 LASTPIN (-5025 3025) $PN L74
J 2
(-5035 3035);
DISPLAY 0.617021 (-5035 3035);
PAINT ORANGE (-5035 3035);
FORCEPROP 2 LASTPIN (-5025 2975) $PN P77
J 2
(-5035 2985);
DISPLAY 0.617021 (-5035 2985);
PAINT ORANGE (-5035 2985);
FORCEPROP 2 LASTPIN (-5025 2875) $PN P73
J 2
(-5035 2885);
DISPLAY 0.617021 (-5035 2885);
PAINT ORANGE (-5035 2885);
FORCEPROP 2 LASTPIN (-5025 2825) $PN M73
J 2
(-5035 2835);
DISPLAY 0.617021 (-5035 2835);
PAINT ORANGE (-5035 2835);
FORCEPROP 2 LASTPIN (-5025 2775) $PN R76
J 2
(-5035 2785);
DISPLAY 0.617021 (-5035 2785);
PAINT ORANGE (-5035 2785);
FORCEPROP 2 LASTPIN (-5025 2725) $PN L76
J 2
(-5035 2735);
DISPLAY 0.617021 (-5035 2735);
PAINT ORANGE (-5035 2735);
FORCEPROP 2 LASTPIN (-5025 2675) $PN N80
J 2
(-5035 2685);
DISPLAY 0.617021 (-5035 2685);
PAINT ORANGE (-5035 2685);
FORCEPROP 2 LASTPIN (-5025 2625) $PN R82
J 2
(-5035 2635);
DISPLAY 0.617021 (-5035 2635);
PAINT ORANGE (-5035 2635);
FORCEPROP 2 LASTPIN (-5025 2575) $PN V79
J 2
(-5035 2585);
DISPLAY 0.617021 (-5035 2585);
PAINT ORANGE (-5035 2585);
FORCEPROP 2 LASTPIN (-5025 2525) $PN W80
J 2
(-5035 2535);
DISPLAY 0.617021 (-5035 2535);
PAINT ORANGE (-5035 2535);
FORCEPROP 2 LASTPIN (-5025 2475) $PN M81
J 2
(-5035 2485);
DISPLAY 0.617021 (-5035 2485);
PAINT ORANGE (-5035 2485);
FORCEPROP 2 LASTPIN (-5025 2425) $PN N82
J 2
(-5035 2435);
DISPLAY 0.617021 (-5035 2435);
PAINT ORANGE (-5035 2435);
FORCEPROP 2 LASTPIN (-5025 2375) $PN T79
J 2
(-5035 2385);
DISPLAY 0.617021 (-5035 2385);
PAINT ORANGE (-5035 2385);
FORCEPROP 2 LASTPIN (-5025 2325) $PN V81
J 2
(-5035 2335);
DISPLAY 0.617021 (-5035 2335);
PAINT ORANGE (-5035 2335);
FORCEPROP 2 LASTPIN (-5025 2275) $PN N84
J 2
(-5035 2285);
DISPLAY 0.617021 (-5035 2285);
PAINT ORANGE (-5035 2285);
FORCEPROP 2 LASTPIN (-5025 2225) $PN N86
J 2
(-5035 2235);
DISPLAY 0.617021 (-5035 2235);
PAINT ORANGE (-5035 2235);
FORCEPROP 2 LASTPIN (-5025 2175) $PN AA84
J 2
(-5035 2185);
DISPLAY 0.617021 (-5035 2185);
PAINT ORANGE (-5035 2185);
FORCEPROP 2 LASTPIN (-5025 2125) $PN AA86
J 2
(-5035 2135);
DISPLAY 0.617021 (-5035 2135);
PAINT ORANGE (-5035 2135);
FORCEPROP 2 LASTPIN (-5025 2075) $PN L84
J 2
(-5035 2085);
DISPLAY 0.617021 (-5035 2085);
PAINT ORANGE (-5035 2085);
FORCEPROP 2 LASTPIN (-5025 2025) $PN L86
J 2
(-5035 2035);
DISPLAY 0.617021 (-5035 2035);
PAINT ORANGE (-5035 2035);
FORCEPROP 2 LASTPIN (-5025 1975) $PN W84
J 2
(-5035 1985);
DISPLAY 0.617021 (-5035 1985);
PAINT ORANGE (-5035 1985);
FORCEPROP 2 LASTPIN (-5025 1925) $PN W86
J 2
(-5035 1935);
DISPLAY 0.617021 (-5035 1935);
PAINT ORANGE (-5035 1935);
FORCEPROP 2 LASTPIN (-5025 1875) $PN AG84
J 2
(-5035 1885);
DISPLAY 0.617021 (-5035 1885);
PAINT ORANGE (-5035 1885);
FORCEPROP 2 LASTPIN (-5025 1825) $PN AG86
J 2
(-5035 1835);
DISPLAY 0.617021 (-5035 1835);
PAINT ORANGE (-5035 1835);
FORCEPROP 2 LASTPIN (-5025 1775) $PN AR84
J 2
(-5035 1785);
DISPLAY 0.617021 (-5035 1785);
PAINT ORANGE (-5035 1785);
FORCEPROP 2 LASTPIN (-5025 1725) $PN AR86
J 2
(-5035 1735);
DISPLAY 0.617021 (-5035 1735);
PAINT ORANGE (-5035 1735);
FORCEPROP 2 LASTPIN (-5025 1675) $PN AE84
J 2
(-5035 1685);
DISPLAY 0.617021 (-5035 1685);
PAINT ORANGE (-5035 1685);
FORCEPROP 2 LASTPIN (-5025 1625) $PN AE86
J 2
(-5035 1635);
DISPLAY 0.617021 (-5035 1635);
PAINT ORANGE (-5035 1635);
FORCEPROP 2 LASTPIN (-5025 1575) $PN AN84
J 2
(-5035 1585);
DISPLAY 0.617021 (-5035 1585);
PAINT ORANGE (-5035 1585);
FORCEPROP 2 LASTPIN (-5025 1525) $PN AN86
J 2
(-5035 1535);
DISPLAY 0.617021 (-5035 1535);
PAINT ORANGE (-5035 1535);
FORCEPROP 2 LASTPIN (-3325 1325) $PN K45
J 0
(-3315 1335);
DISPLAY 0.617021 (-3315 1335);
PAINT ORANGE (-3315 1335);
FORCEPROP 2 LASTPIN (-3325 1275) $PN F45
J 0
(-3315 1285);
DISPLAY 0.617021 (-3315 1285);
PAINT ORANGE (-3315 1285);
FORCEPROP 2 LASTPIN (-3325 1225) $PN D49
J 0
(-3315 1235);
DISPLAY 0.617021 (-3315 1235);
PAINT ORANGE (-3315 1235);
FORCEPROP 2 LASTPIN (-3325 1175) $PN B51
J 0
(-3315 1185);
DISPLAY 0.617021 (-3315 1185);
PAINT ORANGE (-3315 1185);
FORCEPROP 2 LASTPIN (-3325 1125) $PN F47
J 0
(-3315 1135);
DISPLAY 0.617021 (-3315 1135);
PAINT ORANGE (-3315 1135);
FORCEPROP 2 LASTPIN (-3325 1075) $PN D47
J 0
(-3315 1085);
DISPLAY 0.617021 (-3315 1085);
PAINT ORANGE (-3315 1085);
FORCEPROP 2 LASTPIN (-3325 1025) $PN F49
J 0
(-3315 1035);
DISPLAY 0.617021 (-3315 1035);
PAINT ORANGE (-3315 1035);
FORCEPROP 2 LASTPIN (-3325 975) $PN G52
J 0
(-3315 985);
DISPLAY 0.617021 (-3315 985);
PAINT ORANGE (-3315 985);
FORCEPROP 2 LASTPIN (-5025 975) $PN B57
J 2
(-5035 985);
DISPLAY 0.617021 (-5035 985);
PAINT ORANGE (-5035 985);
FORCEPROP 2 LASTPIN (-5025 925) $PN G56
J 2
(-5035 935);
DISPLAY 0.617021 (-5035 935);
PAINT ORANGE (-5035 935);
FORCEPROP 2 LASTPIN (-5025 875) $PN B55
J 2
(-5035 885);
DISPLAY 0.617021 (-5035 885);
PAINT ORANGE (-5035 885);
FORCEPROP 2 LASTPIN (-5025 825) $PN D55
J 2
(-5035 835);
DISPLAY 0.617021 (-5035 835);
PAINT ORANGE (-5035 835);
FORCEPROP 2 LASTPIN (-5025 775) $PN C56
J 2
(-5035 785);
DISPLAY 0.617021 (-5035 785);
PAINT ORANGE (-5035 785);
FORCEPROP 2 LASTPIN (-5025 725) $PN J56
J 2
(-5035 735);
DISPLAY 0.617021 (-5035 735);
PAINT ORANGE (-5035 735);
FORCEPROP 2 LASTPIN (-5025 675) $PN C54
J 2
(-5035 685);
DISPLAY 0.617021 (-5035 685);
PAINT ORANGE (-5035 685);
FORCEPROP 2 LASTPIN (-5025 625) $PN F55
J 2
(-5035 635);
DISPLAY 0.617021 (-5035 635);
PAINT ORANGE (-5035 635);
FORCEPROP 2 LASTPIN (-3325 1825) $PN D63
J 0
(-3315 1835);
DISPLAY 0.617021 (-3315 1835);
PAINT ORANGE (-3315 1835);
FORCEPROP 2 LASTPIN (-3325 1775) $PN B63
J 0
(-3315 1785);
DISPLAY 0.617021 (-3315 1785);
PAINT ORANGE (-3315 1785);
FORCEPROP 2 LASTPIN (-3325 1725) $PN C64
J 0
(-3315 1735);
DISPLAY 0.617021 (-3315 1735);
PAINT ORANGE (-3315 1735);
FORCEPROP 2 LASTPIN (-3325 1675) $PN C62
J 0
(-3315 1685);
DISPLAY 0.617021 (-3315 1685);
PAINT ORANGE (-3315 1685);
FORCEPROP 2 LASTPIN (-5025 525) $PN G46
J 2
(-5035 535);
DISPLAY 0.617021 (-5035 535);
PAINT ORANGE (-5035 535);
FORCEPROP 2 LASTPIN (-3325 875) $PN F63
J 0
(-3315 885);
DISPLAY 0.617021 (-3315 885);
PAINT ORANGE (-3315 885);
FORCEPROP 2 LASTPIN (-3325 825) $PN D61
J 0
(-3315 835);
DISPLAY 0.617021 (-3315 835);
PAINT ORANGE (-3315 835);
FORCEPROP 2 LASTPIN (-3325 775) $PN G54
J 0
(-3315 785);
DISPLAY 0.617021 (-3315 785);
PAINT ORANGE (-3315 785);
FORCEPROP 2 LASTPIN (-3325 725) $PN C52
J 0
(-3315 735);
DISPLAY 0.617021 (-3315 735);
PAINT ORANGE (-3315 735);
FORCEPROP 2 LASTPIN (-3325 575) $PN B61
J 0
(-3315 585);
DISPLAY 0.617021 (-3315 585);
PAINT ORANGE (-3315 585);
FORCEPROP 2 LASTPIN (-3325 625) $PN J60
J 0
(-3315 635);
DISPLAY 0.617021 (-3315 635);
PAINT ORANGE (-3315 635);
FORCEPROP 2 LASTPIN (-5025 2925) $PN M77
J 2
(-5035 2935);
DISPLAY 0.617021 (-5035 2935);
PAINT ORANGE (-5035 2935);
FORCEPROP 1 LAST PACK_TYPE BGA1
J 0
(-4975 4975);
PAINT SKYBLUE (-4975 4975);
DISPLAY INVISIBLE (-4975 4975);
FORCEPROP 2 LAST SEC_TYPE BGA1
J 0
(-4975 4975);
DISPLAY 1.021277 (-4975 4975);
PAINT ORANGE (-4975 4975);
DISPLAY INVISIBLE (-4975 4975);
FORCEPROP 2 LAST CDS_LIB chpset_lib
J 0
(-4175 2575);
PAINT ORANGE (-4175 2575);
DISPLAY INVISIBLE (-4175 2575);
FORCEPROP 2 LAST SEC 3
J 0
(-4975 4975);
DISPLAY 0.680851 (-4975 4975);
PAINT MONO (-4975 4975);
DISPLAY INVISIBLE (-4975 4975);
FORCEPROP 2 LAST CDS_LOCATION U2D1
J 0
(-4975 4925);
DISPLAY 0.617021 (-4975 4925);
PAINT AQUA (-4975 4925);
DISPLAY INVISIBLE (-4975 4925);
FORCEPROP 1 LAST PATH I172
J 0
(-4175 4875);
PAINT GREEN (-4175 4875);
DISPLAY INVISIBLE (-4175 4875);
FORCEADD TAP..6
(-5575 1325);
FORCEPROP 3 LASTPIN (-5525 1325) SIG_NAME M_G_ECC<5>
J 0
(-5515 1335);
DISPLAY 0.659574 (-5515 1335);
PAINT MONO (-5515 1335);
DISPLAY INVISIBLE (-5515 1335);
FORCEPROP 1 LASTPIN (-5525 1325) BN 5
J 0
(-5577 1333);
DISPLAY 0.617021 (-5577 1333);
PAINT GREEN (-5577 1333);
FORCEPROP 2 LAST CDS_LIB mstr_standard
J 0
(-5575 1325);
PAINT MONO (-5575 1325);
DISPLAY INVISIBLE (-5575 1325);
FORCEPROP 1 LAST BODY_TYPE PLUMBING
J 0
(-5575 1275);
DISPLAY 1.595745 (-5575 1275);
PAINT GREEN (-5575 1275);
DISPLAY INVISIBLE (-5575 1275);
FORCEPROP 1 LAST HDL_TAP TRUE
J 0
(-5250 1200);
DISPLAY 1.595745 (-5250 1200);
PAINT GREEN (-5250 1200);
DISPLAY INVISIBLE (-5250 1200);
FORCEPROP 1 LAST PATH I18
J 0
(-5577 1325);
DISPLAY 0.872340 (-5577 1325);
PAINT GREEN (-5577 1325);
DISPLAY INVISIBLE (-5577 1325);
FORCEADD TAP..6
(-5575 1375);
FORCEPROP 3 LASTPIN (-5525 1375) SIG_NAME M_G_ECC<6>
J 0
(-5515 1385);
DISPLAY 0.659574 (-5515 1385);
PAINT MONO (-5515 1385);
DISPLAY INVISIBLE (-5515 1385);
FORCEPROP 1 LASTPIN (-5525 1375) BN 6
J 0
(-5577 1383);
DISPLAY 0.617021 (-5577 1383);
PAINT GREEN (-5577 1383);
FORCEPROP 2 LAST CDS_LIB mstr_standard
J 0
(-5575 1375);
PAINT MONO (-5575 1375);
DISPLAY INVISIBLE (-5575 1375);
FORCEPROP 1 LAST BODY_TYPE PLUMBING
J 0
(-5575 1325);
DISPLAY 1.595745 (-5575 1325);
PAINT GREEN (-5575 1325);
DISPLAY INVISIBLE (-5575 1325);
FORCEPROP 1 LAST HDL_TAP TRUE
J 0
(-5250 1250);
DISPLAY 1.595745 (-5250 1250);
PAINT GREEN (-5250 1250);
DISPLAY INVISIBLE (-5250 1250);
FORCEPROP 1 LAST PATH I19
J 0
(-5577 1375);
DISPLAY 0.872340 (-5577 1375);
PAINT GREEN (-5577 1375);
DISPLAY INVISIBLE (-5577 1375);
FORCEADD OFFPAGE..5
(-6425 825);
FORCEPROP 2 LAST $XR1 78 
J 0
(-6769 825);
DISPLAY 0.638298 (-6769 825);
PAINT MONO (-6769 825);
FORCEPROP 2 LAST $XR0 77 
J 0
(-6679 825);
DISPLAY 0.638298 (-6679 825);
PAINT MONO (-6679 825);
FORCEPROP 2 LAST CDS_LIB mstr_standard
J 0
(-6425 825);
PAINT MONO (-6425 825);
DISPLAY INVISIBLE (-6425 825);
FORCEPROP 1 LAST OFFPAGE TRUE
J 0
(-6100 700);
DISPLAY 1.170213 (-6100 700);
PAINT GREEN (-6100 700);
DISPLAY INVISIBLE (-6100 700);
FORCEPROP 1 LAST COMMENT_BODY TRUE
J 0
(-6325 750);
DISPLAY 1.170213 (-6325 750);
PAINT GREEN (-6325 750);
DISPLAY INVISIBLE (-6325 750);
FORCEPROP 2 LAST PATH I2
J 0
(-6375 900);
DISPLAY 1.021277 (-6375 900);
PAINT ORANGE (-6375 900);
DISPLAY INVISIBLE (-6375 900);
FORCEADD TAP..6
(-5575 1425);
FORCEPROP 3 LASTPIN (-5525 1425) SIG_NAME M_G_ECC<7>
J 0
(-5515 1435);
DISPLAY 0.659574 (-5515 1435);
PAINT MONO (-5515 1435);
DISPLAY INVISIBLE (-5515 1435);
FORCEPROP 1 LASTPIN (-5525 1425) BN 7
J 0
(-5577 1433);
DISPLAY 0.617021 (-5577 1433);
PAINT GREEN (-5577 1433);
FORCEPROP 2 LAST CDS_LIB mstr_standard
J 0
(-5575 1425);
PAINT MONO (-5575 1425);
DISPLAY INVISIBLE (-5575 1425);
FORCEPROP 1 LAST BODY_TYPE PLUMBING
J 0
(-5575 1375);
DISPLAY 1.595745 (-5575 1375);
PAINT GREEN (-5575 1375);
DISPLAY INVISIBLE (-5575 1375);
FORCEPROP 1 LAST HDL_TAP TRUE
J 0
(-5250 1300);
DISPLAY 1.595745 (-5250 1300);
PAINT GREEN (-5250 1300);
DISPLAY INVISIBLE (-5250 1300);
FORCEPROP 1 LAST PATH I20
J 0
(-5577 1425);
DISPLAY 0.872340 (-5577 1425);
PAINT GREEN (-5577 1425);
DISPLAY INVISIBLE (-5577 1425);
FORCEADD TAP..6
(-5575 1525);
FORCEPROP 3 LASTPIN (-5525 1525) SIG_NAME M_G_DQ<0>
J 0
(-5515 1535);
DISPLAY 0.659574 (-5515 1535);
PAINT MONO (-5515 1535);
DISPLAY INVISIBLE (-5515 1535);
FORCEPROP 1 LASTPIN (-5525 1525) BN 0
J 0
(-5577 1533);
DISPLAY 0.617021 (-5577 1533);
PAINT GREEN (-5577 1533);
FORCEPROP 2 LAST CDS_LIB mstr_standard
J 0
(-5575 1525);
PAINT MONO (-5575 1525);
DISPLAY INVISIBLE (-5575 1525);
FORCEPROP 1 LAST BODY_TYPE PLUMBING
J 0
(-5575 1475);
DISPLAY 1.595745 (-5575 1475);
PAINT GREEN (-5575 1475);
DISPLAY INVISIBLE (-5575 1475);
FORCEPROP 1 LAST HDL_TAP TRUE
J 0
(-5250 1400);
DISPLAY 1.595745 (-5250 1400);
PAINT GREEN (-5250 1400);
DISPLAY INVISIBLE (-5250 1400);
FORCEPROP 1 LAST PATH I21
J 0
(-5577 1525);
DISPLAY 0.872340 (-5577 1525);
PAINT GREEN (-5577 1525);
DISPLAY INVISIBLE (-5577 1525);
FORCEADD TAP..6
(-5575 1575);
FORCEPROP 3 LASTPIN (-5525 1575) SIG_NAME M_G_DQ<1>
J 0
(-5515 1585);
DISPLAY 0.659574 (-5515 1585);
PAINT MONO (-5515 1585);
DISPLAY INVISIBLE (-5515 1585);
FORCEPROP 1 LASTPIN (-5525 1575) BN 1
J 0
(-5577 1583);
DISPLAY 0.617021 (-5577 1583);
PAINT GREEN (-5577 1583);
FORCEPROP 2 LAST CDS_LIB mstr_standard
J 0
(-5575 1575);
PAINT MONO (-5575 1575);
DISPLAY INVISIBLE (-5575 1575);
FORCEPROP 1 LAST BODY_TYPE PLUMBING
J 0
(-5575 1525);
DISPLAY 1.595745 (-5575 1525);
PAINT GREEN (-5575 1525);
DISPLAY INVISIBLE (-5575 1525);
FORCEPROP 1 LAST HDL_TAP TRUE
J 0
(-5250 1450);
DISPLAY 1.595745 (-5250 1450);
PAINT GREEN (-5250 1450);
DISPLAY INVISIBLE (-5250 1450);
FORCEPROP 1 LAST PATH I22
J 0
(-5577 1575);
DISPLAY 0.872340 (-5577 1575);
PAINT GREEN (-5577 1575);
DISPLAY INVISIBLE (-5577 1575);
FORCEADD TAP..6
(-5575 1625);
FORCEPROP 3 LASTPIN (-5525 1625) SIG_NAME M_G_DQ<2>
J 0
(-5515 1635);
DISPLAY 0.659574 (-5515 1635);
PAINT MONO (-5515 1635);
DISPLAY INVISIBLE (-5515 1635);
FORCEPROP 1 LASTPIN (-5525 1625) BN 2
J 0
(-5577 1633);
DISPLAY 0.617021 (-5577 1633);
PAINT GREEN (-5577 1633);
FORCEPROP 2 LAST CDS_LIB mstr_standard
J 0
(-5575 1625);
PAINT MONO (-5575 1625);
DISPLAY INVISIBLE (-5575 1625);
FORCEPROP 1 LAST BODY_TYPE PLUMBING
J 0
(-5575 1575);
DISPLAY 1.595745 (-5575 1575);
PAINT GREEN (-5575 1575);
DISPLAY INVISIBLE (-5575 1575);
FORCEPROP 1 LAST HDL_TAP TRUE
J 0
(-5250 1500);
DISPLAY 1.595745 (-5250 1500);
PAINT GREEN (-5250 1500);
DISPLAY INVISIBLE (-5250 1500);
FORCEPROP 1 LAST PATH I23
J 0
(-5577 1625);
DISPLAY 0.872340 (-5577 1625);
PAINT GREEN (-5577 1625);
DISPLAY INVISIBLE (-5577 1625);
FORCEADD TAP..6
(-5575 1675);
FORCEPROP 3 LASTPIN (-5525 1675) SIG_NAME M_G_DQ<3>
J 0
(-5515 1685);
DISPLAY 0.659574 (-5515 1685);
PAINT MONO (-5515 1685);
DISPLAY INVISIBLE (-5515 1685);
FORCEPROP 1 LASTPIN (-5525 1675) BN 3
J 0
(-5577 1683);
DISPLAY 0.617021 (-5577 1683);
PAINT GREEN (-5577 1683);
FORCEPROP 2 LAST CDS_LIB mstr_standard
J 0
(-5575 1675);
PAINT MONO (-5575 1675);
DISPLAY INVISIBLE (-5575 1675);
FORCEPROP 1 LAST BODY_TYPE PLUMBING
J 0
(-5575 1625);
DISPLAY 1.595745 (-5575 1625);
PAINT GREEN (-5575 1625);
DISPLAY INVISIBLE (-5575 1625);
FORCEPROP 1 LAST HDL_TAP TRUE
J 0
(-5250 1550);
DISPLAY 1.595745 (-5250 1550);
PAINT GREEN (-5250 1550);
DISPLAY INVISIBLE (-5250 1550);
FORCEPROP 1 LAST PATH I24
J 0
(-5577 1675);
DISPLAY 0.872340 (-5577 1675);
PAINT GREEN (-5577 1675);
DISPLAY INVISIBLE (-5577 1675);
FORCEADD TAP..6
(-5575 1725);
FORCEPROP 3 LASTPIN (-5525 1725) SIG_NAME M_G_DQ<4>
J 0
(-5515 1735);
DISPLAY 0.659574 (-5515 1735);
PAINT MONO (-5515 1735);
DISPLAY INVISIBLE (-5515 1735);
FORCEPROP 1 LASTPIN (-5525 1725) BN 4
J 0
(-5577 1733);
DISPLAY 0.617021 (-5577 1733);
PAINT GREEN (-5577 1733);
FORCEPROP 2 LAST CDS_LIB mstr_standard
J 0
(-5575 1725);
PAINT MONO (-5575 1725);
DISPLAY INVISIBLE (-5575 1725);
FORCEPROP 1 LAST BODY_TYPE PLUMBING
J 0
(-5575 1675);
DISPLAY 1.595745 (-5575 1675);
PAINT GREEN (-5575 1675);
DISPLAY INVISIBLE (-5575 1675);
FORCEPROP 1 LAST HDL_TAP TRUE
J 0
(-5250 1600);
DISPLAY 1.595745 (-5250 1600);
PAINT GREEN (-5250 1600);
DISPLAY INVISIBLE (-5250 1600);
FORCEPROP 1 LAST PATH I25
J 0
(-5577 1725);
DISPLAY 0.872340 (-5577 1725);
PAINT GREEN (-5577 1725);
DISPLAY INVISIBLE (-5577 1725);
FORCEADD TAP..6
(-5575 1775);
FORCEPROP 3 LASTPIN (-5525 1775) SIG_NAME M_G_DQ<5>
J 0
(-5515 1785);
DISPLAY 0.659574 (-5515 1785);
PAINT MONO (-5515 1785);
DISPLAY INVISIBLE (-5515 1785);
FORCEPROP 1 LASTPIN (-5525 1775) BN 5
J 0
(-5577 1783);
DISPLAY 0.617021 (-5577 1783);
PAINT GREEN (-5577 1783);
FORCEPROP 2 LAST CDS_LIB mstr_standard
J 0
(-5575 1775);
PAINT MONO (-5575 1775);
DISPLAY INVISIBLE (-5575 1775);
FORCEPROP 1 LAST BODY_TYPE PLUMBING
J 0
(-5575 1725);
DISPLAY 1.595745 (-5575 1725);
PAINT GREEN (-5575 1725);
DISPLAY INVISIBLE (-5575 1725);
FORCEPROP 1 LAST HDL_TAP TRUE
J 0
(-5250 1650);
DISPLAY 1.595745 (-5250 1650);
PAINT GREEN (-5250 1650);
DISPLAY INVISIBLE (-5250 1650);
FORCEPROP 1 LAST PATH I26
J 0
(-5577 1775);
DISPLAY 0.872340 (-5577 1775);
PAINT GREEN (-5577 1775);
DISPLAY INVISIBLE (-5577 1775);
FORCEADD TAP..6
(-5575 1825);
FORCEPROP 3 LASTPIN (-5525 1825) SIG_NAME M_G_DQ<6>
J 0
(-5515 1835);
DISPLAY 0.659574 (-5515 1835);
PAINT MONO (-5515 1835);
DISPLAY INVISIBLE (-5515 1835);
FORCEPROP 1 LASTPIN (-5525 1825) BN 6
J 0
(-5577 1833);
DISPLAY 0.617021 (-5577 1833);
PAINT GREEN (-5577 1833);
FORCEPROP 2 LAST CDS_LIB mstr_standard
J 0
(-5575 1825);
PAINT MONO (-5575 1825);
DISPLAY INVISIBLE (-5575 1825);
FORCEPROP 1 LAST BODY_TYPE PLUMBING
J 0
(-5575 1775);
DISPLAY 1.595745 (-5575 1775);
PAINT GREEN (-5575 1775);
DISPLAY INVISIBLE (-5575 1775);
FORCEPROP 1 LAST HDL_TAP TRUE
J 0
(-5250 1700);
DISPLAY 1.595745 (-5250 1700);
PAINT GREEN (-5250 1700);
DISPLAY INVISIBLE (-5250 1700);
FORCEPROP 1 LAST PATH I27
J 0
(-5577 1825);
DISPLAY 0.872340 (-5577 1825);
PAINT GREEN (-5577 1825);
DISPLAY INVISIBLE (-5577 1825);
FORCEADD TAP..6
(-5575 1925);
FORCEPROP 3 LASTPIN (-5525 1925) SIG_NAME M_G_DQ<8>
J 0
(-5515 1935);
DISPLAY 0.659574 (-5515 1935);
PAINT MONO (-5515 1935);
DISPLAY INVISIBLE (-5515 1935);
FORCEPROP 1 LASTPIN (-5525 1925) BN 8
J 0
(-5577 1933);
DISPLAY 0.617021 (-5577 1933);
PAINT GREEN (-5577 1933);
FORCEPROP 2 LAST CDS_LIB mstr_standard
J 0
(-5575 1925);
PAINT MONO (-5575 1925);
DISPLAY INVISIBLE (-5575 1925);
FORCEPROP 1 LAST BODY_TYPE PLUMBING
J 0
(-5575 1875);
DISPLAY 1.595745 (-5575 1875);
PAINT GREEN (-5575 1875);
DISPLAY INVISIBLE (-5575 1875);
FORCEPROP 1 LAST HDL_TAP TRUE
J 0
(-5250 1800);
DISPLAY 1.595745 (-5250 1800);
PAINT GREEN (-5250 1800);
DISPLAY INVISIBLE (-5250 1800);
FORCEPROP 1 LAST PATH I28
J 0
(-5577 1925);
DISPLAY 0.872340 (-5577 1925);
PAINT GREEN (-5577 1925);
DISPLAY INVISIBLE (-5577 1925);
FORCEADD TAP..6
(-5575 1875);
FORCEPROP 3 LASTPIN (-5525 1875) SIG_NAME M_G_DQ<7>
J 0
(-5515 1885);
DISPLAY 0.659574 (-5515 1885);
PAINT MONO (-5515 1885);
DISPLAY INVISIBLE (-5515 1885);
FORCEPROP 1 LASTPIN (-5525 1875) BN 7
J 0
(-5577 1883);
DISPLAY 0.617021 (-5577 1883);
PAINT GREEN (-5577 1883);
FORCEPROP 2 LAST CDS_LIB mstr_standard
J 0
(-5575 1875);
PAINT MONO (-5575 1875);
DISPLAY INVISIBLE (-5575 1875);
FORCEPROP 1 LAST BODY_TYPE PLUMBING
J 0
(-5575 1825);
DISPLAY 1.595745 (-5575 1825);
PAINT GREEN (-5575 1825);
DISPLAY INVISIBLE (-5575 1825);
FORCEPROP 1 LAST HDL_TAP TRUE
J 0
(-5250 1750);
DISPLAY 1.595745 (-5250 1750);
PAINT GREEN (-5250 1750);
DISPLAY INVISIBLE (-5250 1750);
FORCEPROP 1 LAST PATH I29
J 0
(-5577 1875);
DISPLAY 0.872340 (-5577 1875);
PAINT GREEN (-5577 1875);
DISPLAY INVISIBLE (-5577 1875);
FORCEADD OFFPAGE..5
(-6425 1025);
FORCEPROP 2 LAST $XR1 78 
J 0
(-6769 1025);
DISPLAY 0.638298 (-6769 1025);
PAINT MONO (-6769 1025);
FORCEPROP 2 LAST $XR0 77 
J 0
(-6679 1025);
DISPLAY 0.638298 (-6679 1025);
PAINT MONO (-6679 1025);
FORCEPROP 2 LAST CDS_LIB mstr_standard
J 0
(-6425 1025);
PAINT MONO (-6425 1025);
DISPLAY INVISIBLE (-6425 1025);
FORCEPROP 1 LAST OFFPAGE TRUE
J 0
(-6100 900);
DISPLAY 1.170213 (-6100 900);
PAINT GREEN (-6100 900);
DISPLAY INVISIBLE (-6100 900);
FORCEPROP 1 LAST COMMENT_BODY TRUE
J 0
(-6325 950);
DISPLAY 1.170213 (-6325 950);
PAINT GREEN (-6325 950);
DISPLAY INVISIBLE (-6325 950);
FORCEPROP 2 LAST PATH I3
J 0
(-6375 1100);
DISPLAY 1.021277 (-6375 1100);
PAINT ORANGE (-6375 1100);
DISPLAY INVISIBLE (-6375 1100);
FORCEADD TAP..6
(-5575 1975);
FORCEPROP 3 LASTPIN (-5525 1975) SIG_NAME M_G_DQ<9>
J 0
(-5515 1985);
DISPLAY 0.659574 (-5515 1985);
PAINT MONO (-5515 1985);
DISPLAY INVISIBLE (-5515 1985);
FORCEPROP 1 LASTPIN (-5525 1975) BN 9
J 0
(-5577 1983);
DISPLAY 0.617021 (-5577 1983);
PAINT GREEN (-5577 1983);
FORCEPROP 2 LAST CDS_LIB mstr_standard
J 0
(-5575 1975);
PAINT MONO (-5575 1975);
DISPLAY INVISIBLE (-5575 1975);
FORCEPROP 1 LAST BODY_TYPE PLUMBING
J 0
(-5575 1925);
DISPLAY 1.595745 (-5575 1925);
PAINT GREEN (-5575 1925);
DISPLAY INVISIBLE (-5575 1925);
FORCEPROP 1 LAST HDL_TAP TRUE
J 0
(-5250 1850);
DISPLAY 1.595745 (-5250 1850);
PAINT GREEN (-5250 1850);
DISPLAY INVISIBLE (-5250 1850);
FORCEPROP 1 LAST PATH I31
J 0
(-5577 1975);
DISPLAY 0.872340 (-5577 1975);
PAINT GREEN (-5577 1975);
DISPLAY INVISIBLE (-5577 1975);
FORCEADD TAP..6
(-5575 2025);
FORCEPROP 3 LASTPIN (-5525 2025) SIG_NAME M_G_DQ<10>
J 0
(-5515 2035);
DISPLAY 0.659574 (-5515 2035);
PAINT MONO (-5515 2035);
DISPLAY INVISIBLE (-5515 2035);
FORCEPROP 1 LASTPIN (-5525 2025) BN 10
J 0
(-5577 2033);
DISPLAY 0.617021 (-5577 2033);
PAINT GREEN (-5577 2033);
FORCEPROP 2 LAST CDS_LIB mstr_standard
J 0
(-5575 2025);
PAINT MONO (-5575 2025);
DISPLAY INVISIBLE (-5575 2025);
FORCEPROP 1 LAST BODY_TYPE PLUMBING
J 0
(-5575 1975);
DISPLAY 1.595745 (-5575 1975);
PAINT GREEN (-5575 1975);
DISPLAY INVISIBLE (-5575 1975);
FORCEPROP 1 LAST HDL_TAP TRUE
J 0
(-5250 1900);
DISPLAY 1.595745 (-5250 1900);
PAINT GREEN (-5250 1900);
DISPLAY INVISIBLE (-5250 1900);
FORCEPROP 1 LAST PATH I32
J 0
(-5577 2025);
DISPLAY 0.872340 (-5577 2025);
PAINT GREEN (-5577 2025);
DISPLAY INVISIBLE (-5577 2025);
FORCEADD TAP..6
(-5575 2075);
FORCEPROP 3 LASTPIN (-5525 2075) SIG_NAME M_G_DQ<11>
J 0
(-5515 2085);
DISPLAY 0.659574 (-5515 2085);
PAINT MONO (-5515 2085);
DISPLAY INVISIBLE (-5515 2085);
FORCEPROP 1 LASTPIN (-5525 2075) BN 11
J 0
(-5577 2083);
DISPLAY 0.617021 (-5577 2083);
PAINT GREEN (-5577 2083);
FORCEPROP 2 LAST CDS_LIB mstr_standard
J 0
(-5575 2075);
PAINT MONO (-5575 2075);
DISPLAY INVISIBLE (-5575 2075);
FORCEPROP 1 LAST BODY_TYPE PLUMBING
J 0
(-5575 2025);
DISPLAY 1.595745 (-5575 2025);
PAINT GREEN (-5575 2025);
DISPLAY INVISIBLE (-5575 2025);
FORCEPROP 1 LAST HDL_TAP TRUE
J 0
(-5250 1950);
DISPLAY 1.595745 (-5250 1950);
PAINT GREEN (-5250 1950);
DISPLAY INVISIBLE (-5250 1950);
FORCEPROP 1 LAST PATH I33
J 0
(-5577 2075);
DISPLAY 0.872340 (-5577 2075);
PAINT GREEN (-5577 2075);
DISPLAY INVISIBLE (-5577 2075);
FORCEADD TAP..6
(-5575 2125);
FORCEPROP 3 LASTPIN (-5525 2125) SIG_NAME M_G_DQ<12>
J 0
(-5515 2135);
DISPLAY 0.659574 (-5515 2135);
PAINT MONO (-5515 2135);
DISPLAY INVISIBLE (-5515 2135);
FORCEPROP 1 LASTPIN (-5525 2125) BN 12
J 0
(-5577 2133);
DISPLAY 0.617021 (-5577 2133);
PAINT GREEN (-5577 2133);
FORCEPROP 2 LAST CDS_LIB mstr_standard
J 0
(-5575 2125);
PAINT MONO (-5575 2125);
DISPLAY INVISIBLE (-5575 2125);
FORCEPROP 1 LAST BODY_TYPE PLUMBING
J 0
(-5575 2075);
DISPLAY 1.595745 (-5575 2075);
PAINT GREEN (-5575 2075);
DISPLAY INVISIBLE (-5575 2075);
FORCEPROP 1 LAST HDL_TAP TRUE
J 0
(-5250 2000);
DISPLAY 1.595745 (-5250 2000);
PAINT GREEN (-5250 2000);
DISPLAY INVISIBLE (-5250 2000);
FORCEPROP 1 LAST PATH I34
J 0
(-5577 2125);
DISPLAY 0.872340 (-5577 2125);
PAINT GREEN (-5577 2125);
DISPLAY INVISIBLE (-5577 2125);
FORCEADD TAP..6
(-5575 2175);
FORCEPROP 3 LASTPIN (-5525 2175) SIG_NAME M_G_DQ<13>
J 0
(-5515 2185);
DISPLAY 0.659574 (-5515 2185);
PAINT MONO (-5515 2185);
DISPLAY INVISIBLE (-5515 2185);
FORCEPROP 1 LASTPIN (-5525 2175) BN 13
J 0
(-5577 2183);
DISPLAY 0.617021 (-5577 2183);
PAINT GREEN (-5577 2183);
FORCEPROP 2 LAST CDS_LIB mstr_standard
J 0
(-5575 2175);
PAINT MONO (-5575 2175);
DISPLAY INVISIBLE (-5575 2175);
FORCEPROP 1 LAST BODY_TYPE PLUMBING
J 0
(-5575 2125);
DISPLAY 1.595745 (-5575 2125);
PAINT GREEN (-5575 2125);
DISPLAY INVISIBLE (-5575 2125);
FORCEPROP 1 LAST HDL_TAP TRUE
J 0
(-5250 2050);
DISPLAY 1.595745 (-5250 2050);
PAINT GREEN (-5250 2050);
DISPLAY INVISIBLE (-5250 2050);
FORCEPROP 1 LAST PATH I35
J 0
(-5577 2175);
DISPLAY 0.872340 (-5577 2175);
PAINT GREEN (-5577 2175);
DISPLAY INVISIBLE (-5577 2175);
FORCEADD TAP..6
(-5575 2225);
FORCEPROP 3 LASTPIN (-5525 2225) SIG_NAME M_G_DQ<14>
J 0
(-5515 2235);
DISPLAY 0.659574 (-5515 2235);
PAINT MONO (-5515 2235);
DISPLAY INVISIBLE (-5515 2235);
FORCEPROP 1 LASTPIN (-5525 2225) BN 14
J 0
(-5577 2233);
DISPLAY 0.617021 (-5577 2233);
PAINT GREEN (-5577 2233);
FORCEPROP 2 LAST CDS_LIB mstr_standard
J 0
(-5575 2225);
PAINT MONO (-5575 2225);
DISPLAY INVISIBLE (-5575 2225);
FORCEPROP 1 LAST BODY_TYPE PLUMBING
J 0
(-5575 2175);
DISPLAY 1.595745 (-5575 2175);
PAINT GREEN (-5575 2175);
DISPLAY INVISIBLE (-5575 2175);
FORCEPROP 1 LAST HDL_TAP TRUE
J 0
(-5250 2100);
DISPLAY 1.595745 (-5250 2100);
PAINT GREEN (-5250 2100);
DISPLAY INVISIBLE (-5250 2100);
FORCEPROP 1 LAST PATH I36
J 0
(-5577 2225);
DISPLAY 0.872340 (-5577 2225);
PAINT GREEN (-5577 2225);
DISPLAY INVISIBLE (-5577 2225);
FORCEADD TAP..6
(-5575 2275);
FORCEPROP 3 LASTPIN (-5525 2275) SIG_NAME M_G_DQ<15>
J 0
(-5515 2285);
DISPLAY 0.659574 (-5515 2285);
PAINT MONO (-5515 2285);
DISPLAY INVISIBLE (-5515 2285);
FORCEPROP 1 LASTPIN (-5525 2275) BN 15
J 0
(-5577 2283);
DISPLAY 0.617021 (-5577 2283);
PAINT GREEN (-5577 2283);
FORCEPROP 2 LAST CDS_LIB mstr_standard
J 0
(-5575 2275);
PAINT MONO (-5575 2275);
DISPLAY INVISIBLE (-5575 2275);
FORCEPROP 1 LAST BODY_TYPE PLUMBING
J 0
(-5575 2225);
DISPLAY 1.595745 (-5575 2225);
PAINT GREEN (-5575 2225);
DISPLAY INVISIBLE (-5575 2225);
FORCEPROP 1 LAST HDL_TAP TRUE
J 0
(-5250 2150);
DISPLAY 1.595745 (-5250 2150);
PAINT GREEN (-5250 2150);
DISPLAY INVISIBLE (-5250 2150);
FORCEPROP 1 LAST PATH I37
J 0
(-5577 2275);
DISPLAY 0.872340 (-5577 2275);
PAINT GREEN (-5577 2275);
DISPLAY INVISIBLE (-5577 2275);
FORCEADD TAP..6
(-5575 2325);
FORCEPROP 3 LASTPIN (-5525 2325) SIG_NAME M_G_DQ<16>
J 0
(-5515 2335);
DISPLAY 0.659574 (-5515 2335);
PAINT MONO (-5515 2335);
DISPLAY INVISIBLE (-5515 2335);
FORCEPROP 1 LASTPIN (-5525 2325) BN 16
J 0
(-5577 2333);
DISPLAY 0.617021 (-5577 2333);
PAINT GREEN (-5577 2333);
FORCEPROP 2 LAST CDS_LIB mstr_standard
J 0
(-5575 2325);
PAINT MONO (-5575 2325);
DISPLAY INVISIBLE (-5575 2325);
FORCEPROP 1 LAST BODY_TYPE PLUMBING
J 0
(-5575 2275);
DISPLAY 1.595745 (-5575 2275);
PAINT GREEN (-5575 2275);
DISPLAY INVISIBLE (-5575 2275);
FORCEPROP 1 LAST HDL_TAP TRUE
J 0
(-5250 2200);
DISPLAY 1.595745 (-5250 2200);
PAINT GREEN (-5250 2200);
DISPLAY INVISIBLE (-5250 2200);
FORCEPROP 1 LAST PATH I38
J 0
(-5577 2325);
DISPLAY 0.872340 (-5577 2325);
PAINT GREEN (-5577 2325);
DISPLAY INVISIBLE (-5577 2325);
FORCEADD TAP..6
(-5575 2375);
FORCEPROP 3 LASTPIN (-5525 2375) SIG_NAME M_G_DQ<17>
J 0
(-5515 2385);
DISPLAY 0.659574 (-5515 2385);
PAINT MONO (-5515 2385);
DISPLAY INVISIBLE (-5515 2385);
FORCEPROP 1 LASTPIN (-5525 2375) BN 17
J 0
(-5577 2383);
DISPLAY 0.617021 (-5577 2383);
PAINT GREEN (-5577 2383);
FORCEPROP 2 LAST CDS_LIB mstr_standard
J 0
(-5575 2375);
PAINT MONO (-5575 2375);
DISPLAY INVISIBLE (-5575 2375);
FORCEPROP 1 LAST BODY_TYPE PLUMBING
J 0
(-5575 2325);
DISPLAY 1.595745 (-5575 2325);
PAINT GREEN (-5575 2325);
DISPLAY INVISIBLE (-5575 2325);
FORCEPROP 1 LAST HDL_TAP TRUE
J 0
(-5250 2250);
DISPLAY 1.595745 (-5250 2250);
PAINT GREEN (-5250 2250);
DISPLAY INVISIBLE (-5250 2250);
FORCEPROP 1 LAST PATH I39
J 0
(-5577 2375);
DISPLAY 0.872340 (-5577 2375);
PAINT GREEN (-5577 2375);
DISPLAY INVISIBLE (-5577 2375);
FORCEADD OFFPAGE..6
(-6425 1475);
FORCEPROP 2 LAST $XR1 78 
J 0
(-6764 1475);
DISPLAY 0.638298 (-6764 1475);
PAINT MONO (-6764 1475);
FORCEPROP 2 LAST $XR0 77 
J 0
(-6674 1475);
DISPLAY 0.638298 (-6674 1475);
PAINT MONO (-6674 1475);
FORCEPROP 2 LAST CDS_LIB mstr_standard
J 0
(-6425 1475);
PAINT MONO (-6425 1475);
DISPLAY INVISIBLE (-6425 1475);
FORCEPROP 1 LAST OFFPAGE TRUE
J 0
(-6100 1350);
DISPLAY 1.170213 (-6100 1350);
PAINT GREEN (-6100 1350);
DISPLAY INVISIBLE (-6100 1350);
FORCEPROP 1 LAST COMMENT_BODY TRUE
J 0
(-6325 1400);
DISPLAY 1.170213 (-6325 1400);
PAINT GREEN (-6325 1400);
DISPLAY INVISIBLE (-6325 1400);
FORCEPROP 2 LAST PATH I4
J 0
(-6375 1550);
DISPLAY 1.021277 (-6375 1550);
PAINT ORANGE (-6375 1550);
DISPLAY INVISIBLE (-6375 1550);
FORCEADD TAP..6
(-5575 2425);
FORCEPROP 3 LASTPIN (-5525 2425) SIG_NAME M_G_DQ<18>
J 0
(-5515 2435);
DISPLAY 0.659574 (-5515 2435);
PAINT MONO (-5515 2435);
DISPLAY INVISIBLE (-5515 2435);
FORCEPROP 1 LASTPIN (-5525 2425) BN 18
J 0
(-5577 2433);
DISPLAY 0.617021 (-5577 2433);
PAINT GREEN (-5577 2433);
FORCEPROP 2 LAST CDS_LIB mstr_standard
J 0
(-5575 2425);
PAINT MONO (-5575 2425);
DISPLAY INVISIBLE (-5575 2425);
FORCEPROP 1 LAST BODY_TYPE PLUMBING
J 0
(-5575 2375);
DISPLAY 1.595745 (-5575 2375);
PAINT GREEN (-5575 2375);
DISPLAY INVISIBLE (-5575 2375);
FORCEPROP 1 LAST HDL_TAP TRUE
J 0
(-5250 2300);
DISPLAY 1.595745 (-5250 2300);
PAINT GREEN (-5250 2300);
DISPLAY INVISIBLE (-5250 2300);
FORCEPROP 1 LAST PATH I40
J 0
(-5577 2425);
DISPLAY 0.872340 (-5577 2425);
PAINT GREEN (-5577 2425);
DISPLAY INVISIBLE (-5577 2425);
FORCEADD TAP..6
(-5575 2475);
FORCEPROP 3 LASTPIN (-5525 2475) SIG_NAME M_G_DQ<19>
J 0
(-5515 2485);
DISPLAY 0.659574 (-5515 2485);
PAINT MONO (-5515 2485);
DISPLAY INVISIBLE (-5515 2485);
FORCEPROP 1 LASTPIN (-5525 2475) BN 19
J 0
(-5577 2483);
DISPLAY 0.617021 (-5577 2483);
PAINT GREEN (-5577 2483);
FORCEPROP 2 LAST CDS_LIB mstr_standard
J 0
(-5575 2475);
PAINT MONO (-5575 2475);
DISPLAY INVISIBLE (-5575 2475);
FORCEPROP 1 LAST BODY_TYPE PLUMBING
J 0
(-5575 2425);
DISPLAY 1.595745 (-5575 2425);
PAINT GREEN (-5575 2425);
DISPLAY INVISIBLE (-5575 2425);
FORCEPROP 1 LAST HDL_TAP TRUE
J 0
(-5250 2350);
DISPLAY 1.595745 (-5250 2350);
PAINT GREEN (-5250 2350);
DISPLAY INVISIBLE (-5250 2350);
FORCEPROP 1 LAST PATH I41
J 0
(-5577 2475);
DISPLAY 0.872340 (-5577 2475);
PAINT GREEN (-5577 2475);
DISPLAY INVISIBLE (-5577 2475);
FORCEADD TAP..6
(-5575 2525);
FORCEPROP 3 LASTPIN (-5525 2525) SIG_NAME M_G_DQ<20>
J 0
(-5515 2535);
DISPLAY 0.659574 (-5515 2535);
PAINT MONO (-5515 2535);
DISPLAY INVISIBLE (-5515 2535);
FORCEPROP 1 LASTPIN (-5525 2525) BN 20
J 0
(-5577 2533);
DISPLAY 0.617021 (-5577 2533);
PAINT GREEN (-5577 2533);
FORCEPROP 2 LAST CDS_LIB mstr_standard
J 0
(-5575 2525);
PAINT MONO (-5575 2525);
DISPLAY INVISIBLE (-5575 2525);
FORCEPROP 1 LAST BODY_TYPE PLUMBING
J 0
(-5575 2475);
DISPLAY 1.595745 (-5575 2475);
PAINT GREEN (-5575 2475);
DISPLAY INVISIBLE (-5575 2475);
FORCEPROP 1 LAST HDL_TAP TRUE
J 0
(-5250 2400);
DISPLAY 1.595745 (-5250 2400);
PAINT GREEN (-5250 2400);
DISPLAY INVISIBLE (-5250 2400);
FORCEPROP 1 LAST PATH I42
J 0
(-5577 2525);
DISPLAY 0.872340 (-5577 2525);
PAINT GREEN (-5577 2525);
DISPLAY INVISIBLE (-5577 2525);
FORCEADD TAP..6
(-5575 2575);
FORCEPROP 3 LASTPIN (-5525 2575) SIG_NAME M_G_DQ<21>
J 0
(-5515 2585);
DISPLAY 0.659574 (-5515 2585);
PAINT MONO (-5515 2585);
DISPLAY INVISIBLE (-5515 2585);
FORCEPROP 1 LASTPIN (-5525 2575) BN 21
J 0
(-5577 2583);
DISPLAY 0.617021 (-5577 2583);
PAINT GREEN (-5577 2583);
FORCEPROP 2 LAST CDS_LIB mstr_standard
J 0
(-5575 2575);
PAINT MONO (-5575 2575);
DISPLAY INVISIBLE (-5575 2575);
FORCEPROP 1 LAST BODY_TYPE PLUMBING
J 0
(-5575 2525);
DISPLAY 1.595745 (-5575 2525);
PAINT GREEN (-5575 2525);
DISPLAY INVISIBLE (-5575 2525);
FORCEPROP 1 LAST HDL_TAP TRUE
J 0
(-5250 2450);
DISPLAY 1.595745 (-5250 2450);
PAINT GREEN (-5250 2450);
DISPLAY INVISIBLE (-5250 2450);
FORCEPROP 1 LAST PATH I43
J 0
(-5577 2575);
DISPLAY 0.872340 (-5577 2575);
PAINT GREEN (-5577 2575);
DISPLAY INVISIBLE (-5577 2575);
FORCEADD TAP..6
(-5575 2625);
FORCEPROP 3 LASTPIN (-5525 2625) SIG_NAME M_G_DQ<22>
J 0
(-5515 2635);
DISPLAY 0.659574 (-5515 2635);
PAINT MONO (-5515 2635);
DISPLAY INVISIBLE (-5515 2635);
FORCEPROP 1 LASTPIN (-5525 2625) BN 22
J 0
(-5577 2633);
DISPLAY 0.617021 (-5577 2633);
PAINT GREEN (-5577 2633);
FORCEPROP 2 LAST CDS_LIB mstr_standard
J 0
(-5575 2625);
PAINT MONO (-5575 2625);
DISPLAY INVISIBLE (-5575 2625);
FORCEPROP 1 LAST BODY_TYPE PLUMBING
J 0
(-5575 2575);
DISPLAY 1.595745 (-5575 2575);
PAINT GREEN (-5575 2575);
DISPLAY INVISIBLE (-5575 2575);
FORCEPROP 1 LAST HDL_TAP TRUE
J 0
(-5250 2500);
DISPLAY 1.595745 (-5250 2500);
PAINT GREEN (-5250 2500);
DISPLAY INVISIBLE (-5250 2500);
FORCEPROP 1 LAST PATH I44
J 0
(-5577 2625);
DISPLAY 0.872340 (-5577 2625);
PAINT GREEN (-5577 2625);
DISPLAY INVISIBLE (-5577 2625);
FORCEADD TAP..6
(-5575 2675);
FORCEPROP 3 LASTPIN (-5525 2675) SIG_NAME M_G_DQ<23>
J 0
(-5515 2685);
DISPLAY 0.659574 (-5515 2685);
PAINT MONO (-5515 2685);
DISPLAY INVISIBLE (-5515 2685);
FORCEPROP 1 LASTPIN (-5525 2675) BN 23
J 0
(-5577 2683);
DISPLAY 0.617021 (-5577 2683);
PAINT GREEN (-5577 2683);
FORCEPROP 2 LAST CDS_LIB mstr_standard
J 0
(-5575 2675);
PAINT MONO (-5575 2675);
DISPLAY INVISIBLE (-5575 2675);
FORCEPROP 1 LAST BODY_TYPE PLUMBING
J 0
(-5575 2625);
DISPLAY 1.595745 (-5575 2625);
PAINT GREEN (-5575 2625);
DISPLAY INVISIBLE (-5575 2625);
FORCEPROP 1 LAST HDL_TAP TRUE
J 0
(-5250 2550);
DISPLAY 1.595745 (-5250 2550);
PAINT GREEN (-5250 2550);
DISPLAY INVISIBLE (-5250 2550);
FORCEPROP 1 LAST PATH I45
J 0
(-5577 2675);
DISPLAY 0.872340 (-5577 2675);
PAINT GREEN (-5577 2675);
DISPLAY INVISIBLE (-5577 2675);
FORCEADD TAP..6
(-5575 2725);
FORCEPROP 3 LASTPIN (-5525 2725) SIG_NAME M_G_DQ<24>
J 0
(-5515 2735);
DISPLAY 0.659574 (-5515 2735);
PAINT MONO (-5515 2735);
DISPLAY INVISIBLE (-5515 2735);
FORCEPROP 1 LASTPIN (-5525 2725) BN 24
J 0
(-5577 2733);
DISPLAY 0.617021 (-5577 2733);
PAINT GREEN (-5577 2733);
FORCEPROP 2 LAST CDS_LIB mstr_standard
J 0
(-5575 2725);
PAINT MONO (-5575 2725);
DISPLAY INVISIBLE (-5575 2725);
FORCEPROP 1 LAST BODY_TYPE PLUMBING
J 0
(-5575 2675);
DISPLAY 1.595745 (-5575 2675);
PAINT GREEN (-5575 2675);
DISPLAY INVISIBLE (-5575 2675);
FORCEPROP 1 LAST HDL_TAP TRUE
J 0
(-5250 2600);
DISPLAY 1.595745 (-5250 2600);
PAINT GREEN (-5250 2600);
DISPLAY INVISIBLE (-5250 2600);
FORCEPROP 1 LAST PATH I46
J 0
(-5577 2725);
DISPLAY 0.872340 (-5577 2725);
PAINT GREEN (-5577 2725);
DISPLAY INVISIBLE (-5577 2725);
FORCEADD TAP..6
(-5575 2825);
FORCEPROP 3 LASTPIN (-5525 2825) SIG_NAME M_G_DQ<26>
J 0
(-5515 2835);
DISPLAY 0.659574 (-5515 2835);
PAINT MONO (-5515 2835);
DISPLAY INVISIBLE (-5515 2835);
FORCEPROP 1 LASTPIN (-5525 2825) BN 26
J 0
(-5577 2833);
DISPLAY 0.617021 (-5577 2833);
PAINT GREEN (-5577 2833);
FORCEPROP 2 LAST CDS_LIB mstr_standard
J 0
(-5575 2825);
PAINT MONO (-5575 2825);
DISPLAY INVISIBLE (-5575 2825);
FORCEPROP 1 LAST BODY_TYPE PLUMBING
J 0
(-5575 2775);
DISPLAY 1.595745 (-5575 2775);
PAINT GREEN (-5575 2775);
DISPLAY INVISIBLE (-5575 2775);
FORCEPROP 1 LAST HDL_TAP TRUE
J 0
(-5250 2700);
DISPLAY 1.595745 (-5250 2700);
PAINT GREEN (-5250 2700);
DISPLAY INVISIBLE (-5250 2700);
FORCEPROP 1 LAST PATH I47
J 0
(-5577 2825);
DISPLAY 0.872340 (-5577 2825);
PAINT GREEN (-5577 2825);
DISPLAY INVISIBLE (-5577 2825);
FORCEADD TAP..6
(-5575 2775);
FORCEPROP 3 LASTPIN (-5525 2775) SIG_NAME M_G_DQ<25>
J 0
(-5515 2785);
DISPLAY 0.659574 (-5515 2785);
PAINT MONO (-5515 2785);
DISPLAY INVISIBLE (-5515 2785);
FORCEPROP 1 LASTPIN (-5525 2775) BN 25
J 0
(-5577 2783);
DISPLAY 0.617021 (-5577 2783);
PAINT GREEN (-5577 2783);
FORCEPROP 2 LAST CDS_LIB mstr_standard
J 0
(-5575 2775);
PAINT MONO (-5575 2775);
DISPLAY INVISIBLE (-5575 2775);
FORCEPROP 1 LAST BODY_TYPE PLUMBING
J 0
(-5575 2725);
DISPLAY 1.595745 (-5575 2725);
PAINT GREEN (-5575 2725);
DISPLAY INVISIBLE (-5575 2725);
FORCEPROP 1 LAST HDL_TAP TRUE
J 0
(-5250 2650);
DISPLAY 1.595745 (-5250 2650);
PAINT GREEN (-5250 2650);
DISPLAY INVISIBLE (-5250 2650);
FORCEPROP 1 LAST PATH I48
J 0
(-5577 2775);
DISPLAY 0.872340 (-5577 2775);
PAINT GREEN (-5577 2775);
DISPLAY INVISIBLE (-5577 2775);
FORCEADD TAP..6
(-5575 2875);
FORCEPROP 3 LASTPIN (-5525 2875) SIG_NAME M_G_DQ<27>
J 0
(-5515 2885);
DISPLAY 0.659574 (-5515 2885);
PAINT MONO (-5515 2885);
DISPLAY INVISIBLE (-5515 2885);
FORCEPROP 1 LASTPIN (-5525 2875) BN 27
J 0
(-5577 2883);
DISPLAY 0.617021 (-5577 2883);
PAINT GREEN (-5577 2883);
FORCEPROP 2 LAST CDS_LIB mstr_standard
J 0
(-5575 2875);
PAINT MONO (-5575 2875);
DISPLAY INVISIBLE (-5575 2875);
FORCEPROP 1 LAST BODY_TYPE PLUMBING
J 0
(-5575 2825);
DISPLAY 1.595745 (-5575 2825);
PAINT GREEN (-5575 2825);
DISPLAY INVISIBLE (-5575 2825);
FORCEPROP 1 LAST HDL_TAP TRUE
J 0
(-5250 2750);
DISPLAY 1.595745 (-5250 2750);
PAINT GREEN (-5250 2750);
DISPLAY INVISIBLE (-5250 2750);
FORCEPROP 1 LAST PATH I49
J 0
(-5577 2875);
DISPLAY 0.872340 (-5577 2875);
PAINT GREEN (-5577 2875);
DISPLAY INVISIBLE (-5577 2875);
FORCEADD TAP..6
(-5575 625);
FORCEPROP 3 LASTPIN (-5525 625) SIG_NAME M_G_CLK_DN<0>
J 0
(-5515 635);
DISPLAY 0.659574 (-5515 635);
PAINT MONO (-5515 635);
DISPLAY INVISIBLE (-5515 635);
FORCEPROP 1 LASTPIN (-5525 625) BN 0
J 0
(-5577 633);
DISPLAY 0.617021 (-5577 633);
PAINT GREEN (-5577 633);
FORCEPROP 2 LAST CDS_LIB mstr_standard
J 0
(-5575 625);
PAINT MONO (-5575 625);
DISPLAY INVISIBLE (-5575 625);
FORCEPROP 1 LAST BODY_TYPE PLUMBING
J 0
(-5575 575);
DISPLAY 1.595745 (-5575 575);
PAINT GREEN (-5575 575);
DISPLAY INVISIBLE (-5575 575);
FORCEPROP 1 LAST HDL_TAP TRUE
J 0
(-5250 500);
DISPLAY 1.595745 (-5250 500);
PAINT GREEN (-5250 500);
DISPLAY INVISIBLE (-5250 500);
FORCEPROP 1 LAST PATH I5
J 0
(-5577 625);
DISPLAY 0.872340 (-5577 625);
PAINT GREEN (-5577 625);
DISPLAY INVISIBLE (-5577 625);
FORCEADD TAP..6
(-5575 2925);
FORCEPROP 3 LASTPIN (-5525 2925) SIG_NAME M_G_DQ<28>
J 0
(-5515 2935);
DISPLAY 0.659574 (-5515 2935);
PAINT MONO (-5515 2935);
DISPLAY INVISIBLE (-5515 2935);
FORCEPROP 1 LASTPIN (-5525 2925) BN 28
J 0
(-5577 2933);
DISPLAY 0.617021 (-5577 2933);
PAINT GREEN (-5577 2933);
FORCEPROP 2 LAST CDS_LIB mstr_standard
J 0
(-5575 2925);
PAINT MONO (-5575 2925);
DISPLAY INVISIBLE (-5575 2925);
FORCEPROP 1 LAST BODY_TYPE PLUMBING
J 0
(-5575 2875);
DISPLAY 1.595745 (-5575 2875);
PAINT GREEN (-5575 2875);
DISPLAY INVISIBLE (-5575 2875);
FORCEPROP 1 LAST HDL_TAP TRUE
J 0
(-5250 2800);
DISPLAY 1.595745 (-5250 2800);
PAINT GREEN (-5250 2800);
DISPLAY INVISIBLE (-5250 2800);
FORCEPROP 1 LAST PATH I50
J 0
(-5577 2925);
DISPLAY 0.872340 (-5577 2925);
PAINT GREEN (-5577 2925);
DISPLAY INVISIBLE (-5577 2925);
FORCEADD TAP..6
(-5575 2975);
FORCEPROP 3 LASTPIN (-5525 2975) SIG_NAME M_G_DQ<29>
J 0
(-5515 2985);
DISPLAY 0.659574 (-5515 2985);
PAINT MONO (-5515 2985);
DISPLAY INVISIBLE (-5515 2985);
FORCEPROP 1 LASTPIN (-5525 2975) BN 29
J 0
(-5577 2983);
DISPLAY 0.617021 (-5577 2983);
PAINT GREEN (-5577 2983);
FORCEPROP 2 LAST CDS_LIB mstr_standard
J 0
(-5575 2975);
PAINT MONO (-5575 2975);
DISPLAY INVISIBLE (-5575 2975);
FORCEPROP 1 LAST BODY_TYPE PLUMBING
J 0
(-5575 2925);
DISPLAY 1.595745 (-5575 2925);
PAINT GREEN (-5575 2925);
DISPLAY INVISIBLE (-5575 2925);
FORCEPROP 1 LAST HDL_TAP TRUE
J 0
(-5250 2850);
DISPLAY 1.595745 (-5250 2850);
PAINT GREEN (-5250 2850);
DISPLAY INVISIBLE (-5250 2850);
FORCEPROP 1 LAST PATH I51
J 0
(-5577 2975);
DISPLAY 0.872340 (-5577 2975);
PAINT GREEN (-5577 2975);
DISPLAY INVISIBLE (-5577 2975);
FORCEADD TAP..6
(-5575 3075);
FORCEPROP 3 LASTPIN (-5525 3075) SIG_NAME M_G_DQ<31>
J 0
(-5515 3085);
DISPLAY 0.659574 (-5515 3085);
PAINT MONO (-5515 3085);
DISPLAY INVISIBLE (-5515 3085);
FORCEPROP 1 LASTPIN (-5525 3075) BN 31
J 0
(-5577 3083);
DISPLAY 0.617021 (-5577 3083);
PAINT GREEN (-5577 3083);
FORCEPROP 2 LAST CDS_LIB mstr_standard
J 0
(-5575 3075);
PAINT MONO (-5575 3075);
DISPLAY INVISIBLE (-5575 3075);
FORCEPROP 1 LAST BODY_TYPE PLUMBING
J 0
(-5575 3025);
DISPLAY 1.595745 (-5575 3025);
PAINT GREEN (-5575 3025);
DISPLAY INVISIBLE (-5575 3025);
FORCEPROP 1 LAST HDL_TAP TRUE
J 0
(-5250 2950);
DISPLAY 1.595745 (-5250 2950);
PAINT GREEN (-5250 2950);
DISPLAY INVISIBLE (-5250 2950);
FORCEPROP 1 LAST PATH I52
J 0
(-5577 3075);
DISPLAY 0.872340 (-5577 3075);
PAINT GREEN (-5577 3075);
DISPLAY INVISIBLE (-5577 3075);
FORCEADD TAP..6
(-5575 3025);
FORCEPROP 3 LASTPIN (-5525 3025) SIG_NAME M_G_DQ<30>
J 0
(-5515 3035);
DISPLAY 0.659574 (-5515 3035);
PAINT MONO (-5515 3035);
DISPLAY INVISIBLE (-5515 3035);
FORCEPROP 1 LASTPIN (-5525 3025) BN 30
J 0
(-5577 3033);
DISPLAY 0.617021 (-5577 3033);
PAINT GREEN (-5577 3033);
FORCEPROP 2 LAST CDS_LIB mstr_standard
J 0
(-5575 3025);
PAINT MONO (-5575 3025);
DISPLAY INVISIBLE (-5575 3025);
FORCEPROP 1 LAST BODY_TYPE PLUMBING
J 0
(-5575 2975);
DISPLAY 1.595745 (-5575 2975);
PAINT GREEN (-5575 2975);
DISPLAY INVISIBLE (-5575 2975);
FORCEPROP 1 LAST HDL_TAP TRUE
J 0
(-5250 2900);
DISPLAY 1.595745 (-5250 2900);
PAINT GREEN (-5250 2900);
DISPLAY INVISIBLE (-5250 2900);
FORCEPROP 1 LAST PATH I53
J 0
(-5577 3025);
DISPLAY 0.872340 (-5577 3025);
PAINT GREEN (-5577 3025);
DISPLAY INVISIBLE (-5577 3025);
FORCEADD TAP..6
(-5575 3125);
FORCEPROP 3 LASTPIN (-5525 3125) SIG_NAME M_G_DQ<32>
J 0
(-5515 3135);
DISPLAY 0.659574 (-5515 3135);
PAINT MONO (-5515 3135);
DISPLAY INVISIBLE (-5515 3135);
FORCEPROP 1 LASTPIN (-5525 3125) BN 32
J 0
(-5577 3133);
DISPLAY 0.617021 (-5577 3133);
PAINT GREEN (-5577 3133);
FORCEPROP 2 LAST CDS_LIB mstr_standard
J 0
(-5575 3125);
PAINT MONO (-5575 3125);
DISPLAY INVISIBLE (-5575 3125);
FORCEPROP 1 LAST BODY_TYPE PLUMBING
J 0
(-5575 3075);
DISPLAY 1.595745 (-5575 3075);
PAINT GREEN (-5575 3075);
DISPLAY INVISIBLE (-5575 3075);
FORCEPROP 1 LAST HDL_TAP TRUE
J 0
(-5250 3000);
DISPLAY 1.595745 (-5250 3000);
PAINT GREEN (-5250 3000);
DISPLAY INVISIBLE (-5250 3000);
FORCEPROP 1 LAST PATH I54
J 0
(-5577 3125);
DISPLAY 0.872340 (-5577 3125);
PAINT GREEN (-5577 3125);
DISPLAY INVISIBLE (-5577 3125);
FORCEADD TAP..6
(-5575 3175);
FORCEPROP 3 LASTPIN (-5525 3175) SIG_NAME M_G_DQ<33>
J 0
(-5515 3185);
DISPLAY 0.659574 (-5515 3185);
PAINT MONO (-5515 3185);
DISPLAY INVISIBLE (-5515 3185);
FORCEPROP 1 LASTPIN (-5525 3175) BN 33
J 0
(-5577 3183);
DISPLAY 0.617021 (-5577 3183);
PAINT GREEN (-5577 3183);
FORCEPROP 2 LAST CDS_LIB mstr_standard
J 0
(-5575 3175);
PAINT MONO (-5575 3175);
DISPLAY INVISIBLE (-5575 3175);
FORCEPROP 1 LAST BODY_TYPE PLUMBING
J 0
(-5575 3125);
DISPLAY 1.595745 (-5575 3125);
PAINT GREEN (-5575 3125);
DISPLAY INVISIBLE (-5575 3125);
FORCEPROP 1 LAST HDL_TAP TRUE
J 0
(-5250 3050);
DISPLAY 1.595745 (-5250 3050);
PAINT GREEN (-5250 3050);
DISPLAY INVISIBLE (-5250 3050);
FORCEPROP 1 LAST PATH I55
J 0
(-5577 3175);
DISPLAY 0.872340 (-5577 3175);
PAINT GREEN (-5577 3175);
DISPLAY INVISIBLE (-5577 3175);
FORCEADD TAP..6
(-5575 3225);
FORCEPROP 3 LASTPIN (-5525 3225) SIG_NAME M_G_DQ<34>
J 0
(-5515 3235);
DISPLAY 0.659574 (-5515 3235);
PAINT MONO (-5515 3235);
DISPLAY INVISIBLE (-5515 3235);
FORCEPROP 1 LASTPIN (-5525 3225) BN 34
J 0
(-5577 3233);
DISPLAY 0.617021 (-5577 3233);
PAINT GREEN (-5577 3233);
FORCEPROP 2 LAST CDS_LIB mstr_standard
J 0
(-5575 3225);
PAINT MONO (-5575 3225);
DISPLAY INVISIBLE (-5575 3225);
FORCEPROP 1 LAST BODY_TYPE PLUMBING
J 0
(-5575 3175);
DISPLAY 1.595745 (-5575 3175);
PAINT GREEN (-5575 3175);
DISPLAY INVISIBLE (-5575 3175);
FORCEPROP 1 LAST HDL_TAP TRUE
J 0
(-5250 3100);
DISPLAY 1.595745 (-5250 3100);
PAINT GREEN (-5250 3100);
DISPLAY INVISIBLE (-5250 3100);
FORCEPROP 1 LAST PATH I56
J 0
(-5577 3225);
DISPLAY 0.872340 (-5577 3225);
PAINT GREEN (-5577 3225);
DISPLAY INVISIBLE (-5577 3225);
FORCEADD TAP..6
(-5575 3325);
FORCEPROP 3 LASTPIN (-5525 3325) SIG_NAME M_G_DQ<36>
J 0
(-5515 3335);
DISPLAY 0.659574 (-5515 3335);
PAINT MONO (-5515 3335);
DISPLAY INVISIBLE (-5515 3335);
FORCEPROP 1 LASTPIN (-5525 3325) BN 36
J 0
(-5577 3333);
DISPLAY 0.617021 (-5577 3333);
PAINT GREEN (-5577 3333);
FORCEPROP 2 LAST CDS_LIB mstr_standard
J 0
(-5575 3325);
PAINT MONO (-5575 3325);
DISPLAY INVISIBLE (-5575 3325);
FORCEPROP 1 LAST BODY_TYPE PLUMBING
J 0
(-5575 3275);
DISPLAY 1.595745 (-5575 3275);
PAINT GREEN (-5575 3275);
DISPLAY INVISIBLE (-5575 3275);
FORCEPROP 1 LAST HDL_TAP TRUE
J 0
(-5250 3200);
DISPLAY 1.595745 (-5250 3200);
PAINT GREEN (-5250 3200);
DISPLAY INVISIBLE (-5250 3200);
FORCEPROP 1 LAST PATH I57
J 0
(-5577 3325);
DISPLAY 0.872340 (-5577 3325);
PAINT GREEN (-5577 3325);
DISPLAY INVISIBLE (-5577 3325);
FORCEADD TAP..6
(-5575 3275);
FORCEPROP 3 LASTPIN (-5525 3275) SIG_NAME M_G_DQ<35>
J 0
(-5515 3285);
DISPLAY 0.659574 (-5515 3285);
PAINT MONO (-5515 3285);
DISPLAY INVISIBLE (-5515 3285);
FORCEPROP 1 LASTPIN (-5525 3275) BN 35
J 0
(-5577 3283);
DISPLAY 0.617021 (-5577 3283);
PAINT GREEN (-5577 3283);
FORCEPROP 2 LAST CDS_LIB mstr_standard
J 0
(-5575 3275);
PAINT MONO (-5575 3275);
DISPLAY INVISIBLE (-5575 3275);
FORCEPROP 1 LAST BODY_TYPE PLUMBING
J 0
(-5575 3225);
DISPLAY 1.595745 (-5575 3225);
PAINT GREEN (-5575 3225);
DISPLAY INVISIBLE (-5575 3225);
FORCEPROP 1 LAST HDL_TAP TRUE
J 0
(-5250 3150);
DISPLAY 1.595745 (-5250 3150);
PAINT GREEN (-5250 3150);
DISPLAY INVISIBLE (-5250 3150);
FORCEPROP 1 LAST PATH I58
J 0
(-5577 3275);
DISPLAY 0.872340 (-5577 3275);
PAINT GREEN (-5577 3275);
DISPLAY INVISIBLE (-5577 3275);
FORCEADD TAP..6
(-5575 3375);
FORCEPROP 3 LASTPIN (-5525 3375) SIG_NAME M_G_DQ<37>
J 0
(-5515 3385);
DISPLAY 0.659574 (-5515 3385);
PAINT MONO (-5515 3385);
DISPLAY INVISIBLE (-5515 3385);
FORCEPROP 1 LASTPIN (-5525 3375) BN 37
J 0
(-5577 3383);
DISPLAY 0.617021 (-5577 3383);
PAINT GREEN (-5577 3383);
FORCEPROP 2 LAST CDS_LIB mstr_standard
J 0
(-5575 3375);
PAINT MONO (-5575 3375);
DISPLAY INVISIBLE (-5575 3375);
FORCEPROP 1 LAST BODY_TYPE PLUMBING
J 0
(-5575 3325);
DISPLAY 1.595745 (-5575 3325);
PAINT GREEN (-5575 3325);
DISPLAY INVISIBLE (-5575 3325);
FORCEPROP 1 LAST HDL_TAP TRUE
J 0
(-5250 3250);
DISPLAY 1.595745 (-5250 3250);
PAINT GREEN (-5250 3250);
DISPLAY INVISIBLE (-5250 3250);
FORCEPROP 1 LAST PATH I59
J 0
(-5577 3375);
DISPLAY 0.872340 (-5577 3375);
PAINT GREEN (-5577 3375);
DISPLAY INVISIBLE (-5577 3375);
FORCEADD TAP..6
(-5575 675);
FORCEPROP 3 LASTPIN (-5525 675) SIG_NAME M_G_CLK_DN<1>
J 0
(-5515 685);
DISPLAY 0.659574 (-5515 685);
PAINT MONO (-5515 685);
DISPLAY INVISIBLE (-5515 685);
FORCEPROP 1 LASTPIN (-5525 675) BN 1
J 0
(-5577 683);
DISPLAY 0.617021 (-5577 683);
PAINT GREEN (-5577 683);
FORCEPROP 2 LAST CDS_LIB mstr_standard
J 0
(-5575 675);
PAINT MONO (-5575 675);
DISPLAY INVISIBLE (-5575 675);
FORCEPROP 1 LAST BODY_TYPE PLUMBING
J 0
(-5575 625);
DISPLAY 1.595745 (-5575 625);
PAINT GREEN (-5575 625);
DISPLAY INVISIBLE (-5575 625);
FORCEPROP 1 LAST HDL_TAP TRUE
J 0
(-5250 550);
DISPLAY 1.595745 (-5250 550);
PAINT GREEN (-5250 550);
DISPLAY INVISIBLE (-5250 550);
FORCEPROP 1 LAST PATH I6
J 0
(-5577 675);
DISPLAY 0.872340 (-5577 675);
PAINT GREEN (-5577 675);
DISPLAY INVISIBLE (-5577 675);
FORCEADD TAP..6
(-5575 3425);
FORCEPROP 3 LASTPIN (-5525 3425) SIG_NAME M_G_DQ<38>
J 0
(-5515 3435);
DISPLAY 0.659574 (-5515 3435);
PAINT MONO (-5515 3435);
DISPLAY INVISIBLE (-5515 3435);
FORCEPROP 1 LASTPIN (-5525 3425) BN 38
J 0
(-5577 3433);
DISPLAY 0.617021 (-5577 3433);
PAINT GREEN (-5577 3433);
FORCEPROP 2 LAST CDS_LIB mstr_standard
J 0
(-5575 3425);
PAINT MONO (-5575 3425);
DISPLAY INVISIBLE (-5575 3425);
FORCEPROP 1 LAST BODY_TYPE PLUMBING
J 0
(-5575 3375);
DISPLAY 1.595745 (-5575 3375);
PAINT GREEN (-5575 3375);
DISPLAY INVISIBLE (-5575 3375);
FORCEPROP 1 LAST HDL_TAP TRUE
J 0
(-5250 3300);
DISPLAY 1.595745 (-5250 3300);
PAINT GREEN (-5250 3300);
DISPLAY INVISIBLE (-5250 3300);
FORCEPROP 1 LAST PATH I60
J 0
(-5577 3425);
DISPLAY 0.872340 (-5577 3425);
PAINT GREEN (-5577 3425);
DISPLAY INVISIBLE (-5577 3425);
FORCEADD TAP..6
(-5575 3475);
FORCEPROP 3 LASTPIN (-5525 3475) SIG_NAME M_G_DQ<39>
J 0
(-5515 3485);
DISPLAY 0.659574 (-5515 3485);
PAINT MONO (-5515 3485);
DISPLAY INVISIBLE (-5515 3485);
FORCEPROP 1 LASTPIN (-5525 3475) BN 39
J 0
(-5577 3483);
DISPLAY 0.617021 (-5577 3483);
PAINT GREEN (-5577 3483);
FORCEPROP 2 LAST CDS_LIB mstr_standard
J 0
(-5575 3475);
PAINT MONO (-5575 3475);
DISPLAY INVISIBLE (-5575 3475);
FORCEPROP 1 LAST BODY_TYPE PLUMBING
J 0
(-5575 3425);
DISPLAY 1.595745 (-5575 3425);
PAINT GREEN (-5575 3425);
DISPLAY INVISIBLE (-5575 3425);
FORCEPROP 1 LAST HDL_TAP TRUE
J 0
(-5250 3350);
DISPLAY 1.595745 (-5250 3350);
PAINT GREEN (-5250 3350);
DISPLAY INVISIBLE (-5250 3350);
FORCEPROP 1 LAST PATH I61
J 0
(-5577 3475);
DISPLAY 0.872340 (-5577 3475);
PAINT GREEN (-5577 3475);
DISPLAY INVISIBLE (-5577 3475);
FORCEADD TAP..6
(-5575 3525);
FORCEPROP 3 LASTPIN (-5525 3525) SIG_NAME M_G_DQ<40>
J 0
(-5515 3535);
DISPLAY 0.659574 (-5515 3535);
PAINT MONO (-5515 3535);
DISPLAY INVISIBLE (-5515 3535);
FORCEPROP 1 LASTPIN (-5525 3525) BN 40
J 0
(-5577 3533);
DISPLAY 0.617021 (-5577 3533);
PAINT GREEN (-5577 3533);
FORCEPROP 2 LAST CDS_LIB mstr_standard
J 0
(-5575 3525);
PAINT MONO (-5575 3525);
DISPLAY INVISIBLE (-5575 3525);
FORCEPROP 1 LAST BODY_TYPE PLUMBING
J 0
(-5575 3475);
DISPLAY 1.595745 (-5575 3475);
PAINT GREEN (-5575 3475);
DISPLAY INVISIBLE (-5575 3475);
FORCEPROP 1 LAST HDL_TAP TRUE
J 0
(-5250 3400);
DISPLAY 1.595745 (-5250 3400);
PAINT GREEN (-5250 3400);
DISPLAY INVISIBLE (-5250 3400);
FORCEPROP 1 LAST PATH I62
J 0
(-5577 3525);
DISPLAY 0.872340 (-5577 3525);
PAINT GREEN (-5577 3525);
DISPLAY INVISIBLE (-5577 3525);
FORCEADD TAP..6
(-5575 3575);
FORCEPROP 3 LASTPIN (-5525 3575) SIG_NAME M_G_DQ<41>
J 0
(-5515 3585);
DISPLAY 0.659574 (-5515 3585);
PAINT MONO (-5515 3585);
DISPLAY INVISIBLE (-5515 3585);
FORCEPROP 1 LASTPIN (-5525 3575) BN 41
J 0
(-5577 3583);
DISPLAY 0.617021 (-5577 3583);
PAINT GREEN (-5577 3583);
FORCEPROP 2 LAST CDS_LIB mstr_standard
J 0
(-5575 3575);
PAINT MONO (-5575 3575);
DISPLAY INVISIBLE (-5575 3575);
FORCEPROP 1 LAST BODY_TYPE PLUMBING
J 0
(-5575 3525);
DISPLAY 1.595745 (-5575 3525);
PAINT GREEN (-5575 3525);
DISPLAY INVISIBLE (-5575 3525);
FORCEPROP 1 LAST HDL_TAP TRUE
J 0
(-5250 3450);
DISPLAY 1.595745 (-5250 3450);
PAINT GREEN (-5250 3450);
DISPLAY INVISIBLE (-5250 3450);
FORCEPROP 1 LAST PATH I63
J 0
(-5577 3575);
DISPLAY 0.872340 (-5577 3575);
PAINT GREEN (-5577 3575);
DISPLAY INVISIBLE (-5577 3575);
FORCEADD TAP..6
(-5575 3625);
FORCEPROP 3 LASTPIN (-5525 3625) SIG_NAME M_G_DQ<42>
J 0
(-5515 3635);
DISPLAY 0.659574 (-5515 3635);
PAINT MONO (-5515 3635);
DISPLAY INVISIBLE (-5515 3635);
FORCEPROP 1 LASTPIN (-5525 3625) BN 42
J 0
(-5577 3633);
DISPLAY 0.617021 (-5577 3633);
PAINT GREEN (-5577 3633);
FORCEPROP 2 LAST CDS_LIB mstr_standard
J 0
(-5575 3625);
PAINT MONO (-5575 3625);
DISPLAY INVISIBLE (-5575 3625);
FORCEPROP 1 LAST BODY_TYPE PLUMBING
J 0
(-5575 3575);
DISPLAY 1.595745 (-5575 3575);
PAINT GREEN (-5575 3575);
DISPLAY INVISIBLE (-5575 3575);
FORCEPROP 1 LAST HDL_TAP TRUE
J 0
(-5250 3500);
DISPLAY 1.595745 (-5250 3500);
PAINT GREEN (-5250 3500);
DISPLAY INVISIBLE (-5250 3500);
FORCEPROP 1 LAST PATH I64
J 0
(-5577 3625);
DISPLAY 0.872340 (-5577 3625);
PAINT GREEN (-5577 3625);
DISPLAY INVISIBLE (-5577 3625);
FORCEADD TAP..6
(-5575 3675);
FORCEPROP 3 LASTPIN (-5525 3675) SIG_NAME M_G_DQ<43>
J 0
(-5515 3685);
DISPLAY 0.659574 (-5515 3685);
PAINT MONO (-5515 3685);
DISPLAY INVISIBLE (-5515 3685);
FORCEPROP 1 LASTPIN (-5525 3675) BN 43
J 0
(-5577 3683);
DISPLAY 0.617021 (-5577 3683);
PAINT GREEN (-5577 3683);
FORCEPROP 2 LAST CDS_LIB mstr_standard
J 0
(-5575 3675);
PAINT MONO (-5575 3675);
DISPLAY INVISIBLE (-5575 3675);
FORCEPROP 1 LAST BODY_TYPE PLUMBING
J 0
(-5575 3625);
DISPLAY 1.595745 (-5575 3625);
PAINT GREEN (-5575 3625);
DISPLAY INVISIBLE (-5575 3625);
FORCEPROP 1 LAST HDL_TAP TRUE
J 0
(-5250 3550);
DISPLAY 1.595745 (-5250 3550);
PAINT GREEN (-5250 3550);
DISPLAY INVISIBLE (-5250 3550);
FORCEPROP 1 LAST PATH I65
J 0
(-5577 3675);
DISPLAY 0.872340 (-5577 3675);
PAINT GREEN (-5577 3675);
DISPLAY INVISIBLE (-5577 3675);
FORCEADD TAP..6
(-5575 3725);
FORCEPROP 3 LASTPIN (-5525 3725) SIG_NAME M_G_DQ<44>
J 0
(-5515 3735);
DISPLAY 0.659574 (-5515 3735);
PAINT MONO (-5515 3735);
DISPLAY INVISIBLE (-5515 3735);
FORCEPROP 1 LASTPIN (-5525 3725) BN 44
J 0
(-5577 3733);
DISPLAY 0.617021 (-5577 3733);
PAINT GREEN (-5577 3733);
FORCEPROP 2 LAST CDS_LIB mstr_standard
J 0
(-5575 3725);
PAINT MONO (-5575 3725);
DISPLAY INVISIBLE (-5575 3725);
FORCEPROP 1 LAST BODY_TYPE PLUMBING
J 0
(-5575 3675);
DISPLAY 1.595745 (-5575 3675);
PAINT GREEN (-5575 3675);
DISPLAY INVISIBLE (-5575 3675);
FORCEPROP 1 LAST HDL_TAP TRUE
J 0
(-5250 3600);
DISPLAY 1.595745 (-5250 3600);
PAINT GREEN (-5250 3600);
DISPLAY INVISIBLE (-5250 3600);
FORCEPROP 1 LAST PATH I66
J 0
(-5577 3725);
DISPLAY 0.872340 (-5577 3725);
PAINT GREEN (-5577 3725);
DISPLAY INVISIBLE (-5577 3725);
FORCEADD TAP..6
(-5575 3775);
FORCEPROP 3 LASTPIN (-5525 3775) SIG_NAME M_G_DQ<45>
J 0
(-5515 3785);
DISPLAY 0.659574 (-5515 3785);
PAINT MONO (-5515 3785);
DISPLAY INVISIBLE (-5515 3785);
FORCEPROP 1 LASTPIN (-5525 3775) BN 45
J 0
(-5577 3783);
DISPLAY 0.617021 (-5577 3783);
PAINT GREEN (-5577 3783);
FORCEPROP 2 LAST CDS_LIB mstr_standard
J 0
(-5575 3775);
PAINT MONO (-5575 3775);
DISPLAY INVISIBLE (-5575 3775);
FORCEPROP 1 LAST BODY_TYPE PLUMBING
J 0
(-5575 3725);
DISPLAY 1.595745 (-5575 3725);
PAINT GREEN (-5575 3725);
DISPLAY INVISIBLE (-5575 3725);
FORCEPROP 1 LAST HDL_TAP TRUE
J 0
(-5250 3650);
DISPLAY 1.595745 (-5250 3650);
PAINT GREEN (-5250 3650);
DISPLAY INVISIBLE (-5250 3650);
FORCEPROP 1 LAST PATH I67
J 0
(-5577 3775);
DISPLAY 0.872340 (-5577 3775);
PAINT GREEN (-5577 3775);
DISPLAY INVISIBLE (-5577 3775);
FORCEADD TAP..6
(-5575 3825);
FORCEPROP 3 LASTPIN (-5525 3825) SIG_NAME M_G_DQ<46>
J 0
(-5515 3835);
DISPLAY 0.659574 (-5515 3835);
PAINT MONO (-5515 3835);
DISPLAY INVISIBLE (-5515 3835);
FORCEPROP 1 LASTPIN (-5525 3825) BN 46
J 0
(-5577 3833);
DISPLAY 0.617021 (-5577 3833);
PAINT GREEN (-5577 3833);
FORCEPROP 2 LAST CDS_LIB mstr_standard
J 0
(-5575 3825);
PAINT MONO (-5575 3825);
DISPLAY INVISIBLE (-5575 3825);
FORCEPROP 1 LAST BODY_TYPE PLUMBING
J 0
(-5575 3775);
DISPLAY 1.595745 (-5575 3775);
PAINT GREEN (-5575 3775);
DISPLAY INVISIBLE (-5575 3775);
FORCEPROP 1 LAST HDL_TAP TRUE
J 0
(-5250 3700);
DISPLAY 1.595745 (-5250 3700);
PAINT GREEN (-5250 3700);
DISPLAY INVISIBLE (-5250 3700);
FORCEPROP 1 LAST PATH I68
J 0
(-5577 3825);
DISPLAY 0.872340 (-5577 3825);
PAINT GREEN (-5577 3825);
DISPLAY INVISIBLE (-5577 3825);
FORCEADD TAP..6
(-5575 3875);
FORCEPROP 3 LASTPIN (-5525 3875) SIG_NAME M_G_DQ<47>
J 0
(-5515 3885);
DISPLAY 0.659574 (-5515 3885);
PAINT MONO (-5515 3885);
DISPLAY INVISIBLE (-5515 3885);
FORCEPROP 1 LASTPIN (-5525 3875) BN 47
J 0
(-5577 3883);
DISPLAY 0.617021 (-5577 3883);
PAINT GREEN (-5577 3883);
FORCEPROP 2 LAST CDS_LIB mstr_standard
J 0
(-5575 3875);
PAINT MONO (-5575 3875);
DISPLAY INVISIBLE (-5575 3875);
FORCEPROP 1 LAST BODY_TYPE PLUMBING
J 0
(-5575 3825);
DISPLAY 1.595745 (-5575 3825);
PAINT GREEN (-5575 3825);
DISPLAY INVISIBLE (-5575 3825);
FORCEPROP 1 LAST HDL_TAP TRUE
J 0
(-5250 3750);
DISPLAY 1.595745 (-5250 3750);
PAINT GREEN (-5250 3750);
DISPLAY INVISIBLE (-5250 3750);
FORCEPROP 1 LAST PATH I69
J 0
(-5577 3875);
DISPLAY 0.872340 (-5577 3875);
PAINT GREEN (-5577 3875);
DISPLAY INVISIBLE (-5577 3875);
FORCEADD TAP..6
(-5575 775);
FORCEPROP 3 LASTPIN (-5525 775) SIG_NAME M_G_CLK_DN<3>
J 0
(-5515 785);
DISPLAY 0.659574 (-5515 785);
PAINT MONO (-5515 785);
DISPLAY INVISIBLE (-5515 785);
FORCEPROP 1 LASTPIN (-5525 775) BN 3
J 0
(-5577 783);
DISPLAY 0.617021 (-5577 783);
PAINT GREEN (-5577 783);
FORCEPROP 2 LAST CDS_LIB mstr_standard
J 0
(-5575 775);
PAINT MONO (-5575 775);
DISPLAY INVISIBLE (-5575 775);
FORCEPROP 1 LAST BODY_TYPE PLUMBING
J 0
(-5575 725);
DISPLAY 1.595745 (-5575 725);
PAINT GREEN (-5575 725);
DISPLAY INVISIBLE (-5575 725);
FORCEPROP 1 LAST HDL_TAP TRUE
J 0
(-5250 650);
DISPLAY 1.595745 (-5250 650);
PAINT GREEN (-5250 650);
DISPLAY INVISIBLE (-5250 650);
FORCEPROP 1 LAST PATH I7
J 0
(-5577 775);
DISPLAY 0.872340 (-5577 775);
PAINT GREEN (-5577 775);
DISPLAY INVISIBLE (-5577 775);
FORCEADD TAP..6
(-5575 3925);
FORCEPROP 3 LASTPIN (-5525 3925) SIG_NAME M_G_DQ<48>
J 0
(-5515 3935);
DISPLAY 0.659574 (-5515 3935);
PAINT MONO (-5515 3935);
DISPLAY INVISIBLE (-5515 3935);
FORCEPROP 1 LASTPIN (-5525 3925) BN 48
J 0
(-5577 3933);
DISPLAY 0.617021 (-5577 3933);
PAINT GREEN (-5577 3933);
FORCEPROP 2 LAST CDS_LIB mstr_standard
J 0
(-5575 3925);
PAINT MONO (-5575 3925);
DISPLAY INVISIBLE (-5575 3925);
FORCEPROP 1 LAST BODY_TYPE PLUMBING
J 0
(-5575 3875);
DISPLAY 1.595745 (-5575 3875);
PAINT GREEN (-5575 3875);
DISPLAY INVISIBLE (-5575 3875);
FORCEPROP 1 LAST HDL_TAP TRUE
J 0
(-5250 3800);
DISPLAY 1.595745 (-5250 3800);
PAINT GREEN (-5250 3800);
DISPLAY INVISIBLE (-5250 3800);
FORCEPROP 1 LAST PATH I70
J 0
(-5577 3925);
DISPLAY 0.872340 (-5577 3925);
PAINT GREEN (-5577 3925);
DISPLAY INVISIBLE (-5577 3925);
FORCEADD TAP..6
(-5575 3975);
FORCEPROP 3 LASTPIN (-5525 3975) SIG_NAME M_G_DQ<49>
J 0
(-5515 3985);
DISPLAY 0.659574 (-5515 3985);
PAINT MONO (-5515 3985);
DISPLAY INVISIBLE (-5515 3985);
FORCEPROP 1 LASTPIN (-5525 3975) BN 49
J 0
(-5577 3983);
DISPLAY 0.617021 (-5577 3983);
PAINT GREEN (-5577 3983);
FORCEPROP 2 LAST CDS_LIB mstr_standard
J 0
(-5575 3975);
PAINT MONO (-5575 3975);
DISPLAY INVISIBLE (-5575 3975);
FORCEPROP 1 LAST BODY_TYPE PLUMBING
J 0
(-5575 3925);
DISPLAY 1.595745 (-5575 3925);
PAINT GREEN (-5575 3925);
DISPLAY INVISIBLE (-5575 3925);
FORCEPROP 1 LAST HDL_TAP TRUE
J 0
(-5250 3850);
DISPLAY 1.595745 (-5250 3850);
PAINT GREEN (-5250 3850);
DISPLAY INVISIBLE (-5250 3850);
FORCEPROP 1 LAST PATH I71
J 0
(-5577 3975);
DISPLAY 0.872340 (-5577 3975);
PAINT GREEN (-5577 3975);
DISPLAY INVISIBLE (-5577 3975);
FORCEADD OFFPAGE..6
(-6425 4800);
FORCEPROP 2 LAST $XR1 78 
J 0
(-6764 4800);
DISPLAY 0.638298 (-6764 4800);
PAINT MONO (-6764 4800);
FORCEPROP 2 LAST $XR0 77 
J 0
(-6674 4800);
DISPLAY 0.638298 (-6674 4800);
PAINT MONO (-6674 4800);
FORCEPROP 2 LAST CDS_LIB mstr_standard
J 0
(-6425 4800);
PAINT MONO (-6425 4800);
DISPLAY INVISIBLE (-6425 4800);
FORCEPROP 1 LAST OFFPAGE TRUE
J 0
(-6100 4675);
DISPLAY 1.170213 (-6100 4675);
PAINT GREEN (-6100 4675);
DISPLAY INVISIBLE (-6100 4675);
FORCEPROP 1 LAST COMMENT_BODY TRUE
J 0
(-6325 4725);
DISPLAY 1.170213 (-6325 4725);
PAINT GREEN (-6325 4725);
DISPLAY INVISIBLE (-6325 4725);
FORCEPROP 2 LAST PATH I72
J 0
(-6375 4875);
DISPLAY 1.021277 (-6375 4875);
PAINT ORANGE (-6375 4875);
DISPLAY INVISIBLE (-6375 4875);
FORCEADD TAP..6
(-5575 4025);
FORCEPROP 3 LASTPIN (-5525 4025) SIG_NAME M_G_DQ<50>
J 0
(-5515 4035);
DISPLAY 0.659574 (-5515 4035);
PAINT MONO (-5515 4035);
DISPLAY INVISIBLE (-5515 4035);
FORCEPROP 1 LASTPIN (-5525 4025) BN 50
J 0
(-5577 4033);
DISPLAY 0.617021 (-5577 4033);
PAINT GREEN (-5577 4033);
FORCEPROP 2 LAST CDS_LIB mstr_standard
J 0
(-5575 4025);
PAINT MONO (-5575 4025);
DISPLAY INVISIBLE (-5575 4025);
FORCEPROP 1 LAST BODY_TYPE PLUMBING
J 0
(-5575 3975);
DISPLAY 1.595745 (-5575 3975);
PAINT GREEN (-5575 3975);
DISPLAY INVISIBLE (-5575 3975);
FORCEPROP 1 LAST HDL_TAP TRUE
J 0
(-5250 3900);
DISPLAY 1.595745 (-5250 3900);
PAINT GREEN (-5250 3900);
DISPLAY INVISIBLE (-5250 3900);
FORCEPROP 1 LAST PATH I73
J 0
(-5577 4025);
DISPLAY 0.872340 (-5577 4025);
PAINT GREEN (-5577 4025);
DISPLAY INVISIBLE (-5577 4025);
FORCEADD TAP..6
(-5575 4075);
FORCEPROP 3 LASTPIN (-5525 4075) SIG_NAME M_G_DQ<51>
J 0
(-5515 4085);
DISPLAY 0.659574 (-5515 4085);
PAINT MONO (-5515 4085);
DISPLAY INVISIBLE (-5515 4085);
FORCEPROP 1 LASTPIN (-5525 4075) BN 51
J 0
(-5577 4083);
DISPLAY 0.617021 (-5577 4083);
PAINT GREEN (-5577 4083);
FORCEPROP 2 LAST CDS_LIB mstr_standard
J 0
(-5575 4075);
PAINT MONO (-5575 4075);
DISPLAY INVISIBLE (-5575 4075);
FORCEPROP 1 LAST BODY_TYPE PLUMBING
J 0
(-5575 4025);
DISPLAY 1.595745 (-5575 4025);
PAINT GREEN (-5575 4025);
DISPLAY INVISIBLE (-5575 4025);
FORCEPROP 1 LAST HDL_TAP TRUE
J 0
(-5250 3950);
DISPLAY 1.595745 (-5250 3950);
PAINT GREEN (-5250 3950);
DISPLAY INVISIBLE (-5250 3950);
FORCEPROP 1 LAST PATH I74
J 0
(-5577 4075);
DISPLAY 0.872340 (-5577 4075);
PAINT GREEN (-5577 4075);
DISPLAY INVISIBLE (-5577 4075);
FORCEADD TAP..6
(-5575 4125);
FORCEPROP 3 LASTPIN (-5525 4125) SIG_NAME M_G_DQ<52>
J 0
(-5515 4135);
DISPLAY 0.659574 (-5515 4135);
PAINT MONO (-5515 4135);
DISPLAY INVISIBLE (-5515 4135);
FORCEPROP 1 LASTPIN (-5525 4125) BN 52
J 0
(-5577 4133);
DISPLAY 0.617021 (-5577 4133);
PAINT GREEN (-5577 4133);
FORCEPROP 2 LAST CDS_LIB mstr_standard
J 0
(-5575 4125);
PAINT MONO (-5575 4125);
DISPLAY INVISIBLE (-5575 4125);
FORCEPROP 1 LAST BODY_TYPE PLUMBING
J 0
(-5575 4075);
DISPLAY 1.595745 (-5575 4075);
PAINT GREEN (-5575 4075);
DISPLAY INVISIBLE (-5575 4075);
FORCEPROP 1 LAST HDL_TAP TRUE
J 0
(-5250 4000);
DISPLAY 1.595745 (-5250 4000);
PAINT GREEN (-5250 4000);
DISPLAY INVISIBLE (-5250 4000);
FORCEPROP 1 LAST PATH I75
J 0
(-5577 4125);
DISPLAY 0.872340 (-5577 4125);
PAINT GREEN (-5577 4125);
DISPLAY INVISIBLE (-5577 4125);
FORCEADD TAP..6
(-5575 4175);
FORCEPROP 3 LASTPIN (-5525 4175) SIG_NAME M_G_DQ<53>
J 0
(-5515 4185);
DISPLAY 0.659574 (-5515 4185);
PAINT MONO (-5515 4185);
DISPLAY INVISIBLE (-5515 4185);
FORCEPROP 1 LASTPIN (-5525 4175) BN 53
J 0
(-5577 4183);
DISPLAY 0.617021 (-5577 4183);
PAINT GREEN (-5577 4183);
FORCEPROP 2 LAST CDS_LIB mstr_standard
J 0
(-5575 4175);
PAINT MONO (-5575 4175);
DISPLAY INVISIBLE (-5575 4175);
FORCEPROP 1 LAST BODY_TYPE PLUMBING
J 0
(-5575 4125);
DISPLAY 1.595745 (-5575 4125);
PAINT GREEN (-5575 4125);
DISPLAY INVISIBLE (-5575 4125);
FORCEPROP 1 LAST HDL_TAP TRUE
J 0
(-5250 4050);
DISPLAY 1.595745 (-5250 4050);
PAINT GREEN (-5250 4050);
DISPLAY INVISIBLE (-5250 4050);
FORCEPROP 1 LAST PATH I76
J 0
(-5577 4175);
DISPLAY 0.872340 (-5577 4175);
PAINT GREEN (-5577 4175);
DISPLAY INVISIBLE (-5577 4175);
FORCEADD TAP..6
(-5575 4225);
FORCEPROP 3 LASTPIN (-5525 4225) SIG_NAME M_G_DQ<54>
J 0
(-5515 4235);
DISPLAY 0.659574 (-5515 4235);
PAINT MONO (-5515 4235);
DISPLAY INVISIBLE (-5515 4235);
FORCEPROP 1 LASTPIN (-5525 4225) BN 54
J 0
(-5577 4233);
DISPLAY 0.617021 (-5577 4233);
PAINT GREEN (-5577 4233);
FORCEPROP 2 LAST CDS_LIB mstr_standard
J 0
(-5575 4225);
PAINT MONO (-5575 4225);
DISPLAY INVISIBLE (-5575 4225);
FORCEPROP 1 LAST BODY_TYPE PLUMBING
J 0
(-5575 4175);
DISPLAY 1.595745 (-5575 4175);
PAINT GREEN (-5575 4175);
DISPLAY INVISIBLE (-5575 4175);
FORCEPROP 1 LAST HDL_TAP TRUE
J 0
(-5250 4100);
DISPLAY 1.595745 (-5250 4100);
PAINT GREEN (-5250 4100);
DISPLAY INVISIBLE (-5250 4100);
FORCEPROP 1 LAST PATH I77
J 0
(-5577 4225);
DISPLAY 0.872340 (-5577 4225);
PAINT GREEN (-5577 4225);
DISPLAY INVISIBLE (-5577 4225);
FORCEADD TAP..6
(-5575 4275);
FORCEPROP 3 LASTPIN (-5525 4275) SIG_NAME M_G_DQ<55>
J 0
(-5515 4285);
DISPLAY 0.659574 (-5515 4285);
PAINT MONO (-5515 4285);
DISPLAY INVISIBLE (-5515 4285);
FORCEPROP 1 LASTPIN (-5525 4275) BN 55
J 0
(-5577 4283);
DISPLAY 0.617021 (-5577 4283);
PAINT GREEN (-5577 4283);
FORCEPROP 2 LAST CDS_LIB mstr_standard
J 0
(-5575 4275);
PAINT MONO (-5575 4275);
DISPLAY INVISIBLE (-5575 4275);
FORCEPROP 1 LAST BODY_TYPE PLUMBING
J 0
(-5575 4225);
DISPLAY 1.595745 (-5575 4225);
PAINT GREEN (-5575 4225);
DISPLAY INVISIBLE (-5575 4225);
FORCEPROP 1 LAST HDL_TAP TRUE
J 0
(-5250 4150);
DISPLAY 1.595745 (-5250 4150);
PAINT GREEN (-5250 4150);
DISPLAY INVISIBLE (-5250 4150);
FORCEPROP 1 LAST PATH I78
J 0
(-5577 4275);
DISPLAY 0.872340 (-5577 4275);
PAINT GREEN (-5577 4275);
DISPLAY INVISIBLE (-5577 4275);
FORCEADD TAP..6
(-5575 4325);
FORCEPROP 3 LASTPIN (-5525 4325) SIG_NAME M_G_DQ<56>
J 0
(-5515 4335);
DISPLAY 0.659574 (-5515 4335);
PAINT MONO (-5515 4335);
DISPLAY INVISIBLE (-5515 4335);
FORCEPROP 1 LASTPIN (-5525 4325) BN 56
J 0
(-5577 4333);
DISPLAY 0.617021 (-5577 4333);
PAINT GREEN (-5577 4333);
FORCEPROP 2 LAST CDS_LIB mstr_standard
J 0
(-5575 4325);
PAINT MONO (-5575 4325);
DISPLAY INVISIBLE (-5575 4325);
FORCEPROP 1 LAST BODY_TYPE PLUMBING
J 0
(-5575 4275);
DISPLAY 1.595745 (-5575 4275);
PAINT GREEN (-5575 4275);
DISPLAY INVISIBLE (-5575 4275);
FORCEPROP 1 LAST HDL_TAP TRUE
J 0
(-5250 4200);
DISPLAY 1.595745 (-5250 4200);
PAINT GREEN (-5250 4200);
DISPLAY INVISIBLE (-5250 4200);
FORCEPROP 1 LAST PATH I79
J 0
(-5577 4325);
DISPLAY 0.872340 (-5577 4325);
PAINT GREEN (-5577 4325);
DISPLAY INVISIBLE (-5577 4325);
FORCEADD TAP..6
(-5575 725);
FORCEPROP 3 LASTPIN (-5525 725) SIG_NAME M_G_CLK_DN<2>
J 0
(-5515 735);
DISPLAY 0.659574 (-5515 735);
PAINT MONO (-5515 735);
DISPLAY INVISIBLE (-5515 735);
FORCEPROP 1 LASTPIN (-5525 725) BN 2
J 0
(-5577 733);
DISPLAY 0.617021 (-5577 733);
PAINT GREEN (-5577 733);
FORCEPROP 2 LAST CDS_LIB mstr_standard
J 0
(-5575 725);
PAINT MONO (-5575 725);
DISPLAY INVISIBLE (-5575 725);
FORCEPROP 1 LAST BODY_TYPE PLUMBING
J 0
(-5575 675);
DISPLAY 1.595745 (-5575 675);
PAINT GREEN (-5575 675);
DISPLAY INVISIBLE (-5575 675);
FORCEPROP 1 LAST HDL_TAP TRUE
J 0
(-5250 600);
DISPLAY 1.595745 (-5250 600);
PAINT GREEN (-5250 600);
DISPLAY INVISIBLE (-5250 600);
FORCEPROP 1 LAST PATH I8
J 0
(-5577 725);
DISPLAY 0.872340 (-5577 725);
PAINT GREEN (-5577 725);
DISPLAY INVISIBLE (-5577 725);
FORCEADD TAP..6
(-5575 4375);
FORCEPROP 3 LASTPIN (-5525 4375) SIG_NAME M_G_DQ<57>
J 0
(-5515 4385);
DISPLAY 0.659574 (-5515 4385);
PAINT MONO (-5515 4385);
DISPLAY INVISIBLE (-5515 4385);
FORCEPROP 1 LASTPIN (-5525 4375) BN 57
J 0
(-5577 4383);
DISPLAY 0.617021 (-5577 4383);
PAINT GREEN (-5577 4383);
FORCEPROP 2 LAST CDS_LIB mstr_standard
J 0
(-5575 4375);
PAINT MONO (-5575 4375);
DISPLAY INVISIBLE (-5575 4375);
FORCEPROP 1 LAST BODY_TYPE PLUMBING
J 0
(-5575 4325);
DISPLAY 1.595745 (-5575 4325);
PAINT GREEN (-5575 4325);
DISPLAY INVISIBLE (-5575 4325);
FORCEPROP 1 LAST HDL_TAP TRUE
J 0
(-5250 4250);
DISPLAY 1.595745 (-5250 4250);
PAINT GREEN (-5250 4250);
DISPLAY INVISIBLE (-5250 4250);
FORCEPROP 1 LAST PATH I80
J 0
(-5577 4375);
DISPLAY 0.872340 (-5577 4375);
PAINT GREEN (-5577 4375);
DISPLAY INVISIBLE (-5577 4375);
FORCEADD TAP..6
(-5575 4425);
FORCEPROP 3 LASTPIN (-5525 4425) SIG_NAME M_G_DQ<58>
J 0
(-5515 4435);
DISPLAY 0.659574 (-5515 4435);
PAINT MONO (-5515 4435);
DISPLAY INVISIBLE (-5515 4435);
FORCEPROP 1 LASTPIN (-5525 4425) BN 58
J 0
(-5577 4433);
DISPLAY 0.617021 (-5577 4433);
PAINT GREEN (-5577 4433);
FORCEPROP 2 LAST CDS_LIB mstr_standard
J 0
(-5575 4425);
PAINT MONO (-5575 4425);
DISPLAY INVISIBLE (-5575 4425);
FORCEPROP 1 LAST BODY_TYPE PLUMBING
J 0
(-5575 4375);
DISPLAY 1.595745 (-5575 4375);
PAINT GREEN (-5575 4375);
DISPLAY INVISIBLE (-5575 4375);
FORCEPROP 1 LAST HDL_TAP TRUE
J 0
(-5250 4300);
DISPLAY 1.595745 (-5250 4300);
PAINT GREEN (-5250 4300);
DISPLAY INVISIBLE (-5250 4300);
FORCEPROP 1 LAST PATH I81
J 0
(-5577 4425);
DISPLAY 0.872340 (-5577 4425);
PAINT GREEN (-5577 4425);
DISPLAY INVISIBLE (-5577 4425);
FORCEADD TAP..6
(-5575 4475);
FORCEPROP 3 LASTPIN (-5525 4475) SIG_NAME M_G_DQ<59>
J 0
(-5515 4485);
DISPLAY 0.659574 (-5515 4485);
PAINT MONO (-5515 4485);
DISPLAY INVISIBLE (-5515 4485);
FORCEPROP 1 LASTPIN (-5525 4475) BN 59
J 0
(-5577 4483);
DISPLAY 0.617021 (-5577 4483);
PAINT GREEN (-5577 4483);
FORCEPROP 2 LAST CDS_LIB mstr_standard
J 0
(-5575 4475);
PAINT MONO (-5575 4475);
DISPLAY INVISIBLE (-5575 4475);
FORCEPROP 1 LAST BODY_TYPE PLUMBING
J 0
(-5575 4425);
DISPLAY 1.595745 (-5575 4425);
PAINT GREEN (-5575 4425);
DISPLAY INVISIBLE (-5575 4425);
FORCEPROP 1 LAST HDL_TAP TRUE
J 0
(-5250 4350);
DISPLAY 1.595745 (-5250 4350);
PAINT GREEN (-5250 4350);
DISPLAY INVISIBLE (-5250 4350);
FORCEPROP 1 LAST PATH I82
J 0
(-5577 4475);
DISPLAY 0.872340 (-5577 4475);
PAINT GREEN (-5577 4475);
DISPLAY INVISIBLE (-5577 4475);
FORCEADD TAP..6
(-5575 4525);
FORCEPROP 3 LASTPIN (-5525 4525) SIG_NAME M_G_DQ<60>
J 0
(-5515 4535);
DISPLAY 0.659574 (-5515 4535);
PAINT MONO (-5515 4535);
DISPLAY INVISIBLE (-5515 4535);
FORCEPROP 1 LASTPIN (-5525 4525) BN 60
J 0
(-5577 4533);
DISPLAY 0.617021 (-5577 4533);
PAINT GREEN (-5577 4533);
FORCEPROP 2 LAST CDS_LIB mstr_standard
J 0
(-5575 4525);
PAINT MONO (-5575 4525);
DISPLAY INVISIBLE (-5575 4525);
FORCEPROP 1 LAST BODY_TYPE PLUMBING
J 0
(-5575 4475);
DISPLAY 1.595745 (-5575 4475);
PAINT GREEN (-5575 4475);
DISPLAY INVISIBLE (-5575 4475);
FORCEPROP 1 LAST HDL_TAP TRUE
J 0
(-5250 4400);
DISPLAY 1.595745 (-5250 4400);
PAINT GREEN (-5250 4400);
DISPLAY INVISIBLE (-5250 4400);
FORCEPROP 1 LAST PATH I83
J 0
(-5577 4525);
DISPLAY 0.872340 (-5577 4525);
PAINT GREEN (-5577 4525);
DISPLAY INVISIBLE (-5577 4525);
FORCEADD TAP..6
(-5575 4575);
FORCEPROP 3 LASTPIN (-5525 4575) SIG_NAME M_G_DQ<61>
J 0
(-5515 4585);
DISPLAY 0.659574 (-5515 4585);
PAINT MONO (-5515 4585);
DISPLAY INVISIBLE (-5515 4585);
FORCEPROP 1 LASTPIN (-5525 4575) BN 61
J 0
(-5577 4583);
DISPLAY 0.617021 (-5577 4583);
PAINT GREEN (-5577 4583);
FORCEPROP 2 LAST CDS_LIB mstr_standard
J 0
(-5575 4575);
PAINT MONO (-5575 4575);
DISPLAY INVISIBLE (-5575 4575);
FORCEPROP 1 LAST BODY_TYPE PLUMBING
J 0
(-5575 4525);
DISPLAY 1.595745 (-5575 4525);
PAINT GREEN (-5575 4525);
DISPLAY INVISIBLE (-5575 4525);
FORCEPROP 1 LAST HDL_TAP TRUE
J 0
(-5250 4450);
DISPLAY 1.595745 (-5250 4450);
PAINT GREEN (-5250 4450);
DISPLAY INVISIBLE (-5250 4450);
FORCEPROP 1 LAST PATH I84
J 0
(-5577 4575);
DISPLAY 0.872340 (-5577 4575);
PAINT GREEN (-5577 4575);
DISPLAY INVISIBLE (-5577 4575);
FORCEADD TAP..6
(-5575 4625);
FORCEPROP 3 LASTPIN (-5525 4625) SIG_NAME M_G_DQ<62>
J 0
(-5515 4635);
DISPLAY 0.659574 (-5515 4635);
PAINT MONO (-5515 4635);
DISPLAY INVISIBLE (-5515 4635);
FORCEPROP 1 LASTPIN (-5525 4625) BN 62
J 0
(-5577 4633);
DISPLAY 0.617021 (-5577 4633);
PAINT GREEN (-5577 4633);
FORCEPROP 2 LAST CDS_LIB mstr_standard
J 0
(-5575 4625);
PAINT MONO (-5575 4625);
DISPLAY INVISIBLE (-5575 4625);
FORCEPROP 1 LAST BODY_TYPE PLUMBING
J 0
(-5575 4575);
DISPLAY 1.595745 (-5575 4575);
PAINT GREEN (-5575 4575);
DISPLAY INVISIBLE (-5575 4575);
FORCEPROP 1 LAST HDL_TAP TRUE
J 0
(-5250 4500);
DISPLAY 1.595745 (-5250 4500);
PAINT GREEN (-5250 4500);
DISPLAY INVISIBLE (-5250 4500);
FORCEPROP 1 LAST PATH I85
J 0
(-5577 4625);
DISPLAY 0.872340 (-5577 4625);
PAINT GREEN (-5577 4625);
DISPLAY INVISIBLE (-5577 4625);
FORCEADD TAP..6
(-5575 4675);
FORCEPROP 3 LASTPIN (-5525 4675) SIG_NAME M_G_DQ<63>
J 0
(-5515 4685);
DISPLAY 0.659574 (-5515 4685);
PAINT MONO (-5515 4685);
DISPLAY INVISIBLE (-5515 4685);
FORCEPROP 1 LASTPIN (-5525 4675) BN 63
J 0
(-5577 4683);
DISPLAY 0.617021 (-5577 4683);
PAINT GREEN (-5577 4683);
FORCEPROP 2 LAST CDS_LIB mstr_standard
J 0
(-5575 4675);
PAINT MONO (-5575 4675);
DISPLAY INVISIBLE (-5575 4675);
FORCEPROP 1 LAST BODY_TYPE PLUMBING
J 0
(-5575 4625);
DISPLAY 1.595745 (-5575 4625);
PAINT GREEN (-5575 4625);
DISPLAY INVISIBLE (-5575 4625);
FORCEPROP 1 LAST HDL_TAP TRUE
J 0
(-5250 4550);
DISPLAY 1.595745 (-5250 4550);
PAINT GREEN (-5250 4550);
DISPLAY INVISIBLE (-5250 4550);
FORCEPROP 1 LAST PATH I86
J 0
(-5577 4675);
DISPLAY 0.872340 (-5577 4675);
PAINT GREEN (-5577 4675);
DISPLAY INVISIBLE (-5577 4675);
FORCEADD TAP..6
R 2
(-2850 775);
FORCEPROP 3 LASTPIN (-2900 775) SIG_NAME M_G_BA<1>
J 0
(-2890 785);
DISPLAY 0.659574 (-2890 785);
PAINT MONO (-2890 785);
DISPLAY INVISIBLE (-2890 785);
FORCEPROP 1 LASTPIN (-2900 775) BN 1
J 2
(-2848 783);
DISPLAY 0.617021 (-2848 783);
PAINT GREEN (-2848 783);
FORCEPROP 2 LAST CDS_LIB mstr_standard
J 0
(-2850 775);
PAINT MONO (-2850 775);
DISPLAY INVISIBLE (-2850 775);
FORCEPROP 1 LAST BODY_TYPE PLUMBING
J 2
(-2850 725);
DISPLAY 1.595745 (-2850 725);
PAINT GREEN (-2850 725);
DISPLAY INVISIBLE (-2850 725);
FORCEPROP 1 LAST HDL_TAP TRUE
J 2
(-3175 650);
DISPLAY 1.595745 (-3175 650);
PAINT GREEN (-3175 650);
DISPLAY INVISIBLE (-3175 650);
FORCEPROP 1 LAST PATH I87
J 2
(-2848 775);
DISPLAY 0.872340 (-2848 775);
PAINT GREEN (-2848 775);
DISPLAY INVISIBLE (-2848 775);
FORCEADD TAP..6
R 2
(-2850 725);
FORCEPROP 3 LASTPIN (-2900 725) SIG_NAME M_G_BA<0>
J 0
(-2890 735);
DISPLAY 0.659574 (-2890 735);
PAINT MONO (-2890 735);
DISPLAY INVISIBLE (-2890 735);
FORCEPROP 1 LASTPIN (-2900 725) BN 0
J 2
(-2848 733);
DISPLAY 0.617021 (-2848 733);
PAINT GREEN (-2848 733);
FORCEPROP 2 LAST CDS_LIB mstr_standard
J 0
(-2850 725);
PAINT MONO (-2850 725);
DISPLAY INVISIBLE (-2850 725);
FORCEPROP 1 LAST BODY_TYPE PLUMBING
J 2
(-2850 675);
DISPLAY 1.595745 (-2850 675);
PAINT GREEN (-2850 675);
DISPLAY INVISIBLE (-2850 675);
FORCEPROP 1 LAST HDL_TAP TRUE
J 2
(-3175 600);
DISPLAY 1.595745 (-3175 600);
PAINT GREEN (-3175 600);
DISPLAY INVISIBLE (-3175 600);
FORCEPROP 1 LAST PATH I88
J 2
(-2848 725);
DISPLAY 0.872340 (-2848 725);
PAINT GREEN (-2848 725);
DISPLAY INVISIBLE (-2848 725);
FORCEADD TAP..6
R 2
(-2850 825);
FORCEPROP 3 LASTPIN (-2900 825) SIG_NAME M_G_BG<0>
J 0
(-2890 835);
DISPLAY 0.659574 (-2890 835);
PAINT MONO (-2890 835);
DISPLAY INVISIBLE (-2890 835);
FORCEPROP 1 LASTPIN (-2900 825) BN 0
J 2
(-2848 833);
DISPLAY 0.617021 (-2848 833);
PAINT GREEN (-2848 833);
FORCEPROP 2 LAST CDS_LIB mstr_standard
J 0
(-2850 825);
PAINT MONO (-2850 825);
DISPLAY INVISIBLE (-2850 825);
FORCEPROP 1 LAST BODY_TYPE PLUMBING
J 2
(-2850 775);
DISPLAY 1.595745 (-2850 775);
PAINT GREEN (-2850 775);
DISPLAY INVISIBLE (-2850 775);
FORCEPROP 1 LAST HDL_TAP TRUE
J 2
(-3175 700);
DISPLAY 1.595745 (-3175 700);
PAINT GREEN (-3175 700);
DISPLAY INVISIBLE (-3175 700);
FORCEPROP 1 LAST PATH I89
J 2
(-2848 825);
DISPLAY 0.872340 (-2848 825);
PAINT GREEN (-2848 825);
DISPLAY INVISIBLE (-2848 825);
FORCEADD TAP..6
(-5575 875);
FORCEPROP 3 LASTPIN (-5525 875) SIG_NAME M_G_CLK_DP<1>
J 0
(-5515 885);
DISPLAY 0.659574 (-5515 885);
PAINT MONO (-5515 885);
DISPLAY INVISIBLE (-5515 885);
FORCEPROP 1 LASTPIN (-5525 875) BN 1
J 0
(-5577 883);
DISPLAY 0.617021 (-5577 883);
PAINT GREEN (-5577 883);
FORCEPROP 2 LAST CDS_LIB mstr_standard
J 0
(-5575 875);
PAINT MONO (-5575 875);
DISPLAY INVISIBLE (-5575 875);
FORCEPROP 1 LAST BODY_TYPE PLUMBING
J 0
(-5575 825);
DISPLAY 1.595745 (-5575 825);
PAINT GREEN (-5575 825);
DISPLAY INVISIBLE (-5575 825);
FORCEPROP 1 LAST HDL_TAP TRUE
J 0
(-5250 750);
DISPLAY 1.595745 (-5250 750);
PAINT GREEN (-5250 750);
DISPLAY INVISIBLE (-5250 750);
FORCEPROP 1 LAST PATH I9
J 0
(-5577 875);
DISPLAY 0.872340 (-5577 875);
PAINT GREEN (-5577 875);
DISPLAY INVISIBLE (-5577 875);
FORCEADD TAP..6
R 2
(-2850 875);
FORCEPROP 3 LASTPIN (-2900 875) SIG_NAME M_G_BG<1>
J 0
(-2890 885);
DISPLAY 0.659574 (-2890 885);
PAINT MONO (-2890 885);
DISPLAY INVISIBLE (-2890 885);
FORCEPROP 1 LASTPIN (-2900 875) BN 1
J 2
(-2848 883);
DISPLAY 0.617021 (-2848 883);
PAINT GREEN (-2848 883);
FORCEPROP 2 LAST CDS_LIB mstr_standard
J 0
(-2850 875);
PAINT MONO (-2850 875);
DISPLAY INVISIBLE (-2850 875);
FORCEPROP 1 LAST BODY_TYPE PLUMBING
J 2
(-2850 825);
DISPLAY 1.595745 (-2850 825);
PAINT GREEN (-2850 825);
DISPLAY INVISIBLE (-2850 825);
FORCEPROP 1 LAST HDL_TAP TRUE
J 2
(-3175 750);
DISPLAY 1.595745 (-3175 750);
PAINT GREEN (-3175 750);
DISPLAY INVISIBLE (-3175 750);
FORCEPROP 1 LAST PATH I90
J 2
(-2848 875);
DISPLAY 0.872340 (-2848 875);
PAINT GREEN (-2848 875);
DISPLAY INVISIBLE (-2848 875);
FORCEADD TAP..6
R 2
(-2850 1075);
FORCEPROP 3 LASTPIN (-2900 1075) SIG_NAME M_G_CS_N<2>
J 0
(-2890 1085);
DISPLAY 0.659574 (-2890 1085);
PAINT MONO (-2890 1085);
DISPLAY INVISIBLE (-2890 1085);
FORCEPROP 1 LASTPIN (-2900 1075) BN 2
J 2
(-2848 1083);
DISPLAY 0.617021 (-2848 1083);
PAINT GREEN (-2848 1083);
FORCEPROP 2 LAST CDS_LIB mstr_standard
J 0
(-2850 1075);
PAINT MONO (-2850 1075);
DISPLAY INVISIBLE (-2850 1075);
FORCEPROP 1 LAST BODY_TYPE PLUMBING
J 2
(-2850 1025);
DISPLAY 1.595745 (-2850 1025);
PAINT GREEN (-2850 1025);
DISPLAY INVISIBLE (-2850 1025);
FORCEPROP 1 LAST HDL_TAP TRUE
J 2
(-3175 950);
DISPLAY 1.595745 (-3175 950);
PAINT GREEN (-3175 950);
DISPLAY INVISIBLE (-3175 950);
FORCEPROP 1 LAST PATH I91
J 2
(-2848 1075);
DISPLAY 0.872340 (-2848 1075);
PAINT GREEN (-2848 1075);
DISPLAY INVISIBLE (-2848 1075);
FORCEADD TAP..6
R 2
(-2850 1025);
FORCEPROP 3 LASTPIN (-2900 1025) SIG_NAME M_G_CS_N<1>
J 0
(-2890 1035);
DISPLAY 0.659574 (-2890 1035);
PAINT MONO (-2890 1035);
DISPLAY INVISIBLE (-2890 1035);
FORCEPROP 1 LASTPIN (-2900 1025) BN 1
J 2
(-2848 1033);
DISPLAY 0.617021 (-2848 1033);
PAINT GREEN (-2848 1033);
FORCEPROP 2 LAST CDS_LIB mstr_standard
J 0
(-2850 1025);
PAINT MONO (-2850 1025);
DISPLAY INVISIBLE (-2850 1025);
FORCEPROP 1 LAST BODY_TYPE PLUMBING
J 2
(-2850 975);
DISPLAY 1.595745 (-2850 975);
PAINT GREEN (-2850 975);
DISPLAY INVISIBLE (-2850 975);
FORCEPROP 1 LAST HDL_TAP TRUE
J 2
(-3175 900);
DISPLAY 1.595745 (-3175 900);
PAINT GREEN (-3175 900);
DISPLAY INVISIBLE (-3175 900);
FORCEPROP 1 LAST PATH I92
J 2
(-2848 1025);
DISPLAY 0.872340 (-2848 1025);
PAINT GREEN (-2848 1025);
DISPLAY INVISIBLE (-2848 1025);
FORCEADD TAP..6
R 2
(-2850 975);
FORCEPROP 3 LASTPIN (-2900 975) SIG_NAME M_G_CS_N<0>
J 0
(-2890 985);
DISPLAY 0.659574 (-2890 985);
PAINT MONO (-2890 985);
DISPLAY INVISIBLE (-2890 985);
FORCEPROP 1 LASTPIN (-2900 975) BN 0
J 2
(-2848 983);
DISPLAY 0.617021 (-2848 983);
PAINT GREEN (-2848 983);
FORCEPROP 2 LAST CDS_LIB mstr_standard
J 0
(-2850 975);
PAINT MONO (-2850 975);
DISPLAY INVISIBLE (-2850 975);
FORCEPROP 1 LAST BODY_TYPE PLUMBING
J 2
(-2850 925);
DISPLAY 1.595745 (-2850 925);
PAINT GREEN (-2850 925);
DISPLAY INVISIBLE (-2850 925);
FORCEPROP 1 LAST HDL_TAP TRUE
J 2
(-3175 850);
DISPLAY 1.595745 (-3175 850);
PAINT GREEN (-3175 850);
DISPLAY INVISIBLE (-3175 850);
FORCEPROP 1 LAST PATH I93
J 2
(-2848 975);
DISPLAY 0.872340 (-2848 975);
PAINT GREEN (-2848 975);
DISPLAY INVISIBLE (-2848 975);
FORCEADD TAP..6
R 2
(-2850 1175);
FORCEPROP 3 LASTPIN (-2900 1175) SIG_NAME M_G_CS_N<4>
J 0
(-2890 1185);
DISPLAY 0.659574 (-2890 1185);
PAINT MONO (-2890 1185);
DISPLAY INVISIBLE (-2890 1185);
FORCEPROP 1 LASTPIN (-2900 1175) BN 4
J 2
(-2848 1183);
DISPLAY 0.617021 (-2848 1183);
PAINT GREEN (-2848 1183);
FORCEPROP 2 LAST CDS_LIB mstr_standard
J 0
(-2850 1175);
PAINT MONO (-2850 1175);
DISPLAY INVISIBLE (-2850 1175);
FORCEPROP 1 LAST BODY_TYPE PLUMBING
J 2
(-2850 1125);
DISPLAY 1.595745 (-2850 1125);
PAINT GREEN (-2850 1125);
DISPLAY INVISIBLE (-2850 1125);
FORCEPROP 1 LAST HDL_TAP TRUE
J 2
(-3175 1050);
DISPLAY 1.595745 (-3175 1050);
PAINT GREEN (-3175 1050);
DISPLAY INVISIBLE (-3175 1050);
FORCEPROP 1 LAST PATH I94
J 2
(-2848 1175);
DISPLAY 0.872340 (-2848 1175);
PAINT GREEN (-2848 1175);
DISPLAY INVISIBLE (-2848 1175);
FORCEADD TAP..6
R 2
(-2850 1125);
FORCEPROP 3 LASTPIN (-2900 1125) SIG_NAME M_G_CS_N<3>
J 0
(-2890 1135);
DISPLAY 0.659574 (-2890 1135);
PAINT MONO (-2890 1135);
DISPLAY INVISIBLE (-2890 1135);
FORCEPROP 1 LASTPIN (-2900 1125) BN 3
J 2
(-2848 1133);
DISPLAY 0.617021 (-2848 1133);
PAINT GREEN (-2848 1133);
FORCEPROP 2 LAST CDS_LIB mstr_standard
J 0
(-2850 1125);
PAINT MONO (-2850 1125);
DISPLAY INVISIBLE (-2850 1125);
FORCEPROP 1 LAST BODY_TYPE PLUMBING
J 2
(-2850 1075);
DISPLAY 1.595745 (-2850 1075);
PAINT GREEN (-2850 1075);
DISPLAY INVISIBLE (-2850 1075);
FORCEPROP 1 LAST HDL_TAP TRUE
J 2
(-3175 1000);
DISPLAY 1.595745 (-3175 1000);
PAINT GREEN (-3175 1000);
DISPLAY INVISIBLE (-3175 1000);
FORCEPROP 1 LAST PATH I95
J 2
(-2848 1125);
DISPLAY 0.872340 (-2848 1125);
PAINT GREEN (-2848 1125);
DISPLAY INVISIBLE (-2848 1125);
FORCEADD TAP..6
R 2
(-2850 1225);
FORCEPROP 3 LASTPIN (-2900 1225) SIG_NAME M_G_CS_N<5>
J 0
(-2890 1235);
DISPLAY 0.659574 (-2890 1235);
PAINT MONO (-2890 1235);
DISPLAY INVISIBLE (-2890 1235);
FORCEPROP 1 LASTPIN (-2900 1225) BN 5
J 2
(-2848 1233);
DISPLAY 0.617021 (-2848 1233);
PAINT GREEN (-2848 1233);
FORCEPROP 2 LAST CDS_LIB mstr_standard
J 0
(-2850 1225);
PAINT MONO (-2850 1225);
DISPLAY INVISIBLE (-2850 1225);
FORCEPROP 1 LAST BODY_TYPE PLUMBING
J 2
(-2850 1175);
DISPLAY 1.595745 (-2850 1175);
PAINT GREEN (-2850 1175);
DISPLAY INVISIBLE (-2850 1175);
FORCEPROP 1 LAST HDL_TAP TRUE
J 2
(-3175 1100);
DISPLAY 1.595745 (-3175 1100);
PAINT GREEN (-3175 1100);
DISPLAY INVISIBLE (-3175 1100);
FORCEPROP 1 LAST PATH I96
J 2
(-2848 1225);
DISPLAY 0.872340 (-2848 1225);
PAINT GREEN (-2848 1225);
DISPLAY INVISIBLE (-2848 1225);
FORCEADD TAP..6
R 2
(-2850 1275);
FORCEPROP 3 LASTPIN (-2900 1275) SIG_NAME M_G_CS_N<6>
J 0
(-2890 1285);
DISPLAY 0.659574 (-2890 1285);
PAINT MONO (-2890 1285);
DISPLAY INVISIBLE (-2890 1285);
FORCEPROP 1 LASTPIN (-2900 1275) BN 6
J 2
(-2848 1283);
DISPLAY 0.617021 (-2848 1283);
PAINT GREEN (-2848 1283);
FORCEPROP 2 LAST CDS_LIB mstr_standard
J 0
(-2850 1275);
PAINT MONO (-2850 1275);
DISPLAY INVISIBLE (-2850 1275);
FORCEPROP 1 LAST BODY_TYPE PLUMBING
J 2
(-2850 1225);
DISPLAY 1.595745 (-2850 1225);
PAINT GREEN (-2850 1225);
DISPLAY INVISIBLE (-2850 1225);
FORCEPROP 1 LAST HDL_TAP TRUE
J 2
(-3175 1150);
DISPLAY 1.595745 (-3175 1150);
PAINT GREEN (-3175 1150);
DISPLAY INVISIBLE (-3175 1150);
FORCEPROP 1 LAST PATH I97
J 2
(-2848 1275);
DISPLAY 0.872340 (-2848 1275);
PAINT GREEN (-2848 1275);
DISPLAY INVISIBLE (-2848 1275);
FORCEADD TAP..6
R 2
(-2850 1325);
FORCEPROP 3 LASTPIN (-2900 1325) SIG_NAME M_G_CS_N<7>
J 0
(-2890 1335);
DISPLAY 0.659574 (-2890 1335);
PAINT MONO (-2890 1335);
DISPLAY INVISIBLE (-2890 1335);
FORCEPROP 1 LASTPIN (-2900 1325) BN 7
J 2
(-2848 1333);
DISPLAY 0.617021 (-2848 1333);
PAINT GREEN (-2848 1333);
FORCEPROP 2 LAST CDS_LIB mstr_standard
J 0
(-2850 1325);
PAINT MONO (-2850 1325);
DISPLAY INVISIBLE (-2850 1325);
FORCEPROP 1 LAST BODY_TYPE PLUMBING
J 2
(-2850 1275);
DISPLAY 1.595745 (-2850 1275);
PAINT GREEN (-2850 1275);
DISPLAY INVISIBLE (-2850 1275);
FORCEPROP 1 LAST HDL_TAP TRUE
J 2
(-3175 1200);
DISPLAY 1.595745 (-3175 1200);
PAINT GREEN (-3175 1200);
DISPLAY INVISIBLE (-3175 1200);
FORCEPROP 1 LAST PATH I98
J 2
(-2848 1325);
DISPLAY 0.872340 (-2848 1325);
PAINT GREEN (-2848 1325);
DISPLAY INVISIBLE (-2848 1325);
FORCEADD TAP..6
R 2
(-2850 1425);
FORCEPROP 3 LASTPIN (-2900 1425) SIG_NAME M_G_ODT<0>
J 0
(-2890 1435);
DISPLAY 0.659574 (-2890 1435);
PAINT MONO (-2890 1435);
DISPLAY INVISIBLE (-2890 1435);
FORCEPROP 1 LASTPIN (-2900 1425) BN 0
J 2
(-2848 1433);
DISPLAY 0.617021 (-2848 1433);
PAINT GREEN (-2848 1433);
FORCEPROP 2 LAST CDS_LIB mstr_standard
J 0
(-2850 1425);
PAINT MONO (-2850 1425);
DISPLAY INVISIBLE (-2850 1425);
FORCEPROP 1 LAST BODY_TYPE PLUMBING
J 2
(-2850 1375);
DISPLAY 1.595745 (-2850 1375);
PAINT GREEN (-2850 1375);
DISPLAY INVISIBLE (-2850 1375);
FORCEPROP 1 LAST HDL_TAP TRUE
J 2
(-3175 1300);
DISPLAY 1.595745 (-3175 1300);
PAINT GREEN (-3175 1300);
DISPLAY INVISIBLE (-3175 1300);
FORCEPROP 1 LAST PATH I99
J 2
(-2848 1425);
DISPLAY 0.872340 (-2848 1425);
PAINT GREEN (-2848 1425);
DISPLAY INVISIBLE (-2848 1425);
FORCEADD DESIGN_NOTE..1
(-6275 350);
FORCEPROP 0 LAST L1 CPU SYMBOLS 1-30 ARE PRELIMINARY AND SUBJECT TO CHANGE
J 0
(-6475 225);
DISPLAY 1.021277 (-6475 225);
PAINT ORANGE (-6475 225);
FORCEPROP 2 LAST CDS_LIB mstr_symbols
J 0
(-6275 350);
PAINT ORANGE (-6275 350);
DISPLAY INVISIBLE (-6275 350);
FORCEPROP 1 LAST COMMENT_BODY TRUE
J 0
(-6250 450);
DISPLAY 0.978723 (-6250 450);
PAINT ORANGE (-6250 450);
DISPLAY INVISIBLE (-6250 450);
FORCEADD PRELIM..10
(-4215 2565);
PAINT GRAY (-4215 2565);
FORCEPROP 2 LAST CDS_LIB mstr_misc
J 0
(-4215 2565);
PAINT ORANGE (-4215 2565);
DISPLAY INVISIBLE (-4215 2565);
FORCEPROP 1 LAST COMMENT_BODY TRUE
J 0
(-4215 2565);
PAINT ORANGE (-4215 2565);
DISPLAY INVISIBLE (-4215 2565);
FORCEADD INTEL_CORP_BPAGE..1
(0 0);
FORCEPROP 1 LAST CDS_CON_LAST_MODIFIED Fri Jun 16 17:48:22 2017
J 0
(-1425 325);
DISPLAY 1.340426 (-1425 325);
PAINT GREEN (-1425 325);
DISPLAY INVISIBLE (-1425 325);
FORCEPROP 1 LAST CUSTOM_TXT_CDS <CURRENT_DESIGN_SHEET> OF <TOTAL_DESIGN_SHEETS>
J 0
(-500 25);
PAINT ORANGE (-500 25);
FORCEPROP 1 LAST CUSTOM_TXT_CDS <CON_LAST_MODIFIED>
J 0
(-4000 100);
PAINT ORANGE (-4000 100);
FORCEPROP 2 LAST CUSTOM_TXT_CDS <XR_PAGE_TITLE>
J 0
(-7890 5250);
DISPLAY 0.638298 (-7890 5250);
PAINT PINK (-7890 5250);
DISPLAY INVISIBLE (-7890 5250);
FORCEPROP 1 LAST SCH_TITLE SKYLAKE - SKT1 - 3 OF 21
J 0
(-7950 50);
DISPLAY 1.212766 (-7950 50);
PAINT GREEN (-7950 50);
FORCEPROP 2 LAST PAGE_BORDER TRUE
J 0
(-7890 5250);
DISPLAY 0.851064 (-7890 5250);
PAINT PINK (-7890 5250);
DISPLAY INVISIBLE (-7890 5250);
FORCEPROP 2 LAST CDS_LIB mstr_symbols
J 0
(0 0);
PAINT ORANGE (0 0);
DISPLAY INVISIBLE (0 0);
FORCEPROP 1 LAST COMMENT_BODY TRUE
J 0
(12 12);
DISPLAY 0.638298 (12 12);
PAINT GREEN (12 12);
DISPLAY INVISIBLE (12 12);
FORCEPROP 2 LAST CDS_XR_PAGE_TITLE CR-57 : @BASEBOARD_FAB2_LIB.BASEBOARD_FAB2(SCH_1):PAGE57
J 0
(-7890 5250);
DISPLAY 0.638298 (-7890 5250);
PAINT PINK (-7890 5250);
DISPLAY INVISIBLE (-7890 5250);
WIRE 17 -1 (-2800 3850)(-2800 3900);
WIRE 17 -1 (-2800 3900)(-2800 3950);
WIRE 17 -1 (-2800 3950)(-2800 4000);
WIRE 17 -1 (-2800 4000)(-2800 4050);
WIRE 17 -1 (-2800 4050)(-2800 4100);
WIRE 17 -1 (-2800 4100)(-2800 4150);
WIRE 17 -1 (-2800 4150)(-2800 4200);
WIRE 17 -1 (-2800 4200)(-2800 4250);
WIRE 17 -1 (-2800 4250)(-2800 4300);
WIRE 17 -1 (-2800 4300)(-2800 4350);
WIRE 17 -1 (-2800 4350)(-2800 4400);
WIRE 17 -1 (-2800 4400)(-2800 4450);
WIRE 17 -1 (-2800 4450)(-2800 4500);
WIRE 17 -1 (-2800 4500)(-2800 4550);
WIRE 17 -1 (-2800 4550)(-2800 4600);
WIRE 17 -1 (-2800 4600)(-2800 4650);
WIRE 17 -1 (-2050 4750)(-2800 4750);
FORCEPROP 2 LAST SIG_NAME M_G_DQS_DP<17:0>
J 0
(-2700 4760);
DISPLAY 0.617021 (-2700 4760);
PAINT ORANGE (-2700 4760);
WIRE 17 -1 (-2800 4650)(-2800 4700);
WIRE 17 -1 (-2800 4700)(-2800 4750);
WIRE 17 -1 (-2800 2900)(-2800 2950);
WIRE 17 -1 (-2800 2950)(-2800 3000);
WIRE 17 -1 (-2800 3000)(-2800 3050);
WIRE 17 -1 (-2800 3050)(-2800 3100);
WIRE 17 -1 (-2800 3100)(-2800 3150);
WIRE 17 -1 (-2800 3150)(-2800 3200);
WIRE 17 -1 (-2800 3200)(-2800 3250);
WIRE 17 -1 (-2800 3250)(-2800 3300);
WIRE 17 -1 (-2800 3300)(-2800 3350);
WIRE 17 -1 (-2800 3350)(-2800 3400);
WIRE 17 -1 (-2800 3400)(-2800 3450);
WIRE 17 -1 (-2800 3450)(-2800 3500);
WIRE 17 -1 (-2800 3500)(-2800 3550);
WIRE 17 -1 (-2800 3550)(-2800 3600);
WIRE 17 -1 (-2800 3600)(-2800 3650);
WIRE 17 -1 (-2800 3650)(-2800 3700);
WIRE 17 -1 (-2050 3775)(-2800 3775);
FORCEPROP 2 LAST SIG_NAME M_G_DQS_DN<17:0>
J 0
(-2700 3785);
DISPLAY 0.617021 (-2700 3785);
PAINT ORANGE (-2700 3785);
WIRE 17 -1 (-2800 3700)(-2800 3750);
WIRE 17 -1 (-2800 3750)(-2800 3775);
WIRE 17 -1 (-2800 1950)(-2800 2000);
WIRE 17 -1 (-2800 2000)(-2800 2050);
WIRE 17 -1 (-2800 2050)(-2800 2100);
WIRE 17 -1 (-2800 2100)(-2800 2150);
WIRE 17 -1 (-2800 2150)(-2800 2200);
WIRE 17 -1 (-2800 2200)(-2800 2250);
WIRE 17 -1 (-2800 2250)(-2800 2300);
WIRE 17 -1 (-2800 2300)(-2800 2350);
WIRE 17 -1 (-2800 2350)(-2800 2400);
WIRE 17 -1 (-2800 2400)(-2800 2450);
WIRE 17 -1 (-2800 2450)(-2800 2500);
WIRE 17 -1 (-2800 2500)(-2800 2550);
WIRE 17 -1 (-2800 2550)(-2800 2600);
WIRE 17 -1 (-2800 2600)(-2800 2650);
WIRE 17 -1 (-2800 2650)(-2800 2700);
WIRE 17 -1 (-2800 2700)(-2800 2750);
WIRE 17 -1 (-2050 2825)(-2800 2825);
FORCEPROP 2 LAST SIG_NAME M_G_MA<17:0>
J 0
(-2700 2835);
DISPLAY 0.617021 (-2700 2835);
PAINT ORANGE (-2700 2835);
WIRE 17 -1 (-2800 2750)(-2800 2800);
WIRE 17 -1 (-2800 2800)(-2800 2825);
WIRE 17 -1 (-2050 825)(-2800 825);
FORCEPROP 2 LAST SIG_NAME M_G_BA<1:0>
J 0
(-2700 835);
DISPLAY 0.617021 (-2700 835);
PAINT ORANGE (-2700 835);
WIRE 17 -1 (-2800 750)(-2800 800);
WIRE 17 -1 (-2800 800)(-2800 825);
WIRE 17 -1 (-2050 925)(-2800 925);
FORCEPROP 2 LAST SIG_NAME M_G_BG<1:0>
J 0
(-2700 935);
DISPLAY 0.617021 (-2700 935);
PAINT ORANGE (-2700 935);
WIRE 17 -1 (-2800 900)(-2800 925);
WIRE 17 -1 (-2800 850)(-2800 900);
WIRE 17 -1 (-2800 1700)(-2800 1750);
WIRE 17 -1 (-2800 1750)(-2800 1800);
WIRE 17 -1 (-2050 1875)(-2800 1875);
FORCEPROP 2 LAST SIG_NAME M_G_CKE<3:0>
J 0
(-2700 1885);
DISPLAY 0.617021 (-2700 1885);
PAINT ORANGE (-2700 1885);
WIRE 17 -1 (-2800 1800)(-2800 1850);
WIRE 17 -1 (-2800 1850)(-2800 1875);
WIRE 17 -1 (-2800 1000)(-2800 1050);
WIRE 17 -1 (-2800 1050)(-2800 1100);
WIRE 17 -1 (-2800 1100)(-2800 1150);
WIRE 17 -1 (-2800 1150)(-2800 1200);
WIRE 17 -1 (-2800 1200)(-2800 1250);
WIRE 17 -1 (-2800 1250)(-2800 1300);
WIRE 17 -1 (-2050 1375)(-2800 1375);
FORCEPROP 2 LAST SIG_NAME M_G_CS_N<7:0>
J 0
(-2700 1385);
DISPLAY 0.617021 (-2700 1385);
PAINT ORANGE (-2700 1385);
WIRE 17 -1 (-2800 1300)(-2800 1350);
WIRE 17 -1 (-2800 1350)(-2800 1375);
WIRE 17 -1 (-2800 1450)(-2800 1500);
WIRE 17 -1 (-2800 1500)(-2800 1550);
WIRE 17 -1 (-2050 1625)(-2800 1625);
FORCEPROP 2 LAST SIG_NAME M_G_ODT<3:0>
J 0
(-2700 1635);
DISPLAY 0.617021 (-2700 1635);
PAINT ORANGE (-2700 1635);
WIRE 17 -1 (-2800 1550)(-2800 1600);
WIRE 17 -1 (-2800 1600)(-2800 1625);
WIRE 17 -1 (-5625 1550)(-5625 1600);
WIRE 17 -1 (-5625 1600)(-5625 1650);
WIRE 17 -1 (-5625 1650)(-5625 1700);
WIRE 17 -1 (-5625 1700)(-5625 1750);
WIRE 17 -1 (-5625 1750)(-5625 1800);
WIRE 17 -1 (-5625 1800)(-5625 1850);
WIRE 17 -1 (-5625 1850)(-5625 1900);
WIRE 17 -1 (-5625 1900)(-5625 1950);
WIRE 17 -1 (-5625 1950)(-5625 2000);
WIRE 17 -1 (-5625 2000)(-5625 2050);
WIRE 17 -1 (-5625 2050)(-5625 2100);
WIRE 17 -1 (-5625 2100)(-5625 2150);
WIRE 17 -1 (-5625 2150)(-5625 2200);
WIRE 17 -1 (-5625 2200)(-5625 2250);
WIRE 17 -1 (-5625 2250)(-5625 2300);
WIRE 17 -1 (-5625 2300)(-5625 2350);
WIRE 17 -1 (-5625 2350)(-5625 2400);
WIRE 17 -1 (-5625 2400)(-5625 2450);
WIRE 17 -1 (-5625 2450)(-5625 2500);
WIRE 17 -1 (-5625 2500)(-5625 2550);
WIRE 17 -1 (-5625 2550)(-5625 2600);
WIRE 17 -1 (-5625 2600)(-5625 2650);
WIRE 17 -1 (-5625 2650)(-5625 2700);
WIRE 17 -1 (-5625 2700)(-5625 2750);
WIRE 17 -1 (-5625 2750)(-5625 2800);
WIRE 17 -1 (-5625 2800)(-5625 2850);
WIRE 17 -1 (-5625 2850)(-5625 2900);
WIRE 17 -1 (-5625 2900)(-5625 2950);
WIRE 17 -1 (-5625 2950)(-5625 3000);
WIRE 17 -1 (-5625 3000)(-5625 3050);
WIRE 17 -1 (-5625 3050)(-5625 3100);
WIRE 17 -1 (-5625 3100)(-5625 3150);
WIRE 17 -1 (-5625 3150)(-5625 3200);
WIRE 17 -1 (-5625 3200)(-5625 3250);
WIRE 17 -1 (-5625 3250)(-5625 3300);
WIRE 17 -1 (-5625 3300)(-5625 3350);
WIRE 17 -1 (-5625 3350)(-5625 3400);
WIRE 17 -1 (-5625 3400)(-5625 3450);
WIRE 17 -1 (-5625 3450)(-5625 3500);
WIRE 17 -1 (-5625 3500)(-5625 3550);
WIRE 17 -1 (-5625 3550)(-5625 3600);
WIRE 17 -1 (-5625 3600)(-5625 3650);
WIRE 17 -1 (-5625 3650)(-5625 3700);
WIRE 17 -1 (-5625 3700)(-5625 3750);
WIRE 17 -1 (-5625 3750)(-5625 3800);
WIRE 17 -1 (-5625 3800)(-5625 3850);
WIRE 17 -1 (-5625 3850)(-5625 3900);
WIRE 17 -1 (-5625 3900)(-5625 3950);
WIRE 17 -1 (-5625 3950)(-5625 4000);
WIRE 17 -1 (-5625 4000)(-5625 4050);
WIRE 17 -1 (-5625 4050)(-5625 4100);
WIRE 17 -1 (-5625 4100)(-5625 4150);
WIRE 17 -1 (-5625 4150)(-5625 4200);
WIRE 17 -1 (-5625 4200)(-5625 4250);
WIRE 17 -1 (-5625 4250)(-5625 4300);
WIRE 17 -1 (-5625 4300)(-5625 4350);
WIRE 17 -1 (-5625 4350)(-5625 4400);
WIRE 17 -1 (-5625 4400)(-5625 4450);
WIRE 17 -1 (-5625 4450)(-5625 4500);
WIRE 17 -1 (-5625 4500)(-5625 4550);
WIRE 17 -1 (-5625 4550)(-5625 4600);
WIRE 17 -1 (-5625 4600)(-5625 4650);
WIRE 17 -1 (-5625 4800)(-6375 4800);
FORCEPROP 2 LAST SIG_NAME M_G_DQ<63:0>
J 0
(-6325 4810);
DISPLAY 0.617021 (-6325 4810);
PAINT ORANGE (-6325 4810);
WIRE 17 -1 (-5625 4650)(-5625 4700);
WIRE 17 -1 (-5625 4700)(-5625 4800);
WIRE 17 -1 (-5625 650)(-5625 700);
WIRE 17 -1 (-5625 700)(-5625 750);
WIRE 17 -1 (-5625 825)(-6375 825);
FORCEPROP 2 LAST SIG_NAME M_G_CLK_DN<3:0>
J 0
(-6325 835);
DISPLAY 0.617021 (-6325 835);
PAINT ORANGE (-6325 835);
WIRE 17 -1 (-5625 750)(-5625 800);
WIRE 17 -1 (-5625 800)(-5625 825);
WIRE 17 -1 (-5625 850)(-5625 900);
WIRE 17 -1 (-5625 900)(-5625 950);
WIRE 17 -1 (-5625 1025)(-6375 1025);
FORCEPROP 2 LAST SIG_NAME M_G_CLK_DP<3:0>
J 0
(-6325 1035);
DISPLAY 0.617021 (-6325 1035);
PAINT ORANGE (-6325 1035);
WIRE 17 -1 (-5625 950)(-5625 1000);
WIRE 17 -1 (-5625 1000)(-5625 1025);
WIRE 17 -1 (-5625 1100)(-5625 1150);
WIRE 17 -1 (-5625 1150)(-5625 1200);
WIRE 17 -1 (-5625 1200)(-5625 1250);
WIRE 17 -1 (-5625 1250)(-5625 1300);
WIRE 17 -1 (-5625 1300)(-5625 1350);
WIRE 17 -1 (-5625 1350)(-5625 1400);
WIRE 17 -1 (-5625 1475)(-6375 1475);
FORCEPROP 2 LAST SIG_NAME M_G_ECC<7:0>
J 0
(-6325 1485);
DISPLAY 0.617021 (-6325 1485);
PAINT ORANGE (-6325 1485);
WIRE 17 -1 (-5625 1400)(-5625 1450);
WIRE 17 -1 (-5625 1450)(-5625 1475);
WIRE 16 -1 (-5025 4275)(-5525 4275);
WIRE 16 -1 (-5025 1125)(-5525 1125);
WIRE 16 -1 (-5525 3575)(-5025 3575);
WIRE 16 -1 (-5525 2925)(-5025 2925);
WIRE 16 -1 (-5025 4125)(-5525 4125);
WIRE 16 -1 (-3325 1525)(-2900 1525);
WIRE 16 -1 (-5525 3225)(-5025 3225);
WIRE 16 -1 (-5025 1675)(-5525 1675);
WIRE 16 -1 (-5525 3125)(-5025 3125);
WIRE 16 -1 (-5025 525)(-6375 525);
FORCEPROP 2 LAST SIG_NAME M_G_C<2>
J 0
(-6325 535);
DISPLAY 0.617021 (-6325 535);
PAINT ORANGE (-6325 535);
WIRE 16 -1 (-5025 1075)(-5525 1075);
WIRE 16 -1 (-5025 1175)(-5525 1175);
WIRE 16 -1 (-5025 1225)(-5525 1225);
WIRE 16 -1 (-5025 1275)(-5525 1275);
WIRE 16 -1 (-5025 1325)(-5525 1325);
WIRE 16 -1 (-5025 1375)(-5525 1375);
WIRE 16 -1 (-5025 1425)(-5525 1425);
WIRE 16 -1 (-5525 1525)(-5025 1525);
WIRE 16 -1 (-5525 1575)(-5025 1575);
WIRE 16 -1 (-5525 1625)(-5025 1625);
WIRE 16 -1 (-5525 1725)(-5025 1725);
WIRE 16 -1 (-5525 1775)(-5025 1775);
WIRE 16 -1 (-5025 1825)(-5525 1825);
WIRE 16 -1 (-5525 1875)(-5025 1875);
WIRE 16 -1 (-5525 1925)(-5025 1925);
WIRE 16 -1 (-5525 1975)(-5025 1975);
WIRE 16 -1 (-5525 2025)(-5025 2025);
WIRE 16 -1 (-5025 825)(-5525 825);
WIRE 16 -1 (-5025 875)(-5525 875);
WIRE 16 -1 (-5025 925)(-5525 925);
WIRE 16 -1 (-5025 975)(-5525 975);
WIRE 16 -1 (-5025 625)(-5525 625);
WIRE 16 -1 (-5025 675)(-5525 675);
WIRE 16 -1 (-5025 725)(-5525 725);
WIRE 16 -1 (-5025 775)(-5525 775);
WIRE 16 -1 (-5525 2075)(-5025 2075);
WIRE 16 -1 (-5525 2125)(-5025 2125);
WIRE 16 -1 (-5525 2175)(-5025 2175);
WIRE 16 -1 (-5525 2225)(-5025 2225);
WIRE 16 -1 (-5025 2275)(-5525 2275);
WIRE 16 -1 (-5525 2325)(-5025 2325);
WIRE 16 -1 (-5525 2375)(-5025 2375);
WIRE 16 -1 (-5025 2425)(-5525 2425);
WIRE 16 -1 (-5525 2475)(-5025 2475);
WIRE 16 -1 (-5525 2525)(-5025 2525);
WIRE 16 -1 (-5525 2575)(-5025 2575);
WIRE 16 -1 (-5525 2625)(-5025 2625);
WIRE 16 -1 (-5025 2675)(-5525 2675);
WIRE 16 -1 (-5525 2725)(-5025 2725);
WIRE 16 -1 (-5525 2775)(-5025 2775);
WIRE 16 -1 (-5525 2825)(-5025 2825);
WIRE 16 -1 (-5525 2875)(-5025 2875);
WIRE 16 -1 (-5525 2975)(-5025 2975);
WIRE 16 -1 (-5025 3025)(-5525 3025);
WIRE 16 -1 (-5525 3075)(-5025 3075);
WIRE 16 -1 (-5525 3175)(-5025 3175);
WIRE 16 -1 (-5525 3275)(-5025 3275);
WIRE 16 -1 (-5525 3325)(-5025 3325);
WIRE 16 -1 (-5025 3375)(-5525 3375);
WIRE 16 -1 (-5525 3425)(-5025 3425);
WIRE 16 -1 (-5525 3475)(-5025 3475);
WIRE 16 -1 (-5025 3525)(-5525 3525);
WIRE 16 -1 (-5525 3625)(-5025 3625);
WIRE 16 -1 (-5025 3675)(-5525 3675);
WIRE 16 -1 (-5025 3725)(-5525 3725);
WIRE 16 -1 (-5025 3775)(-5525 3775);
WIRE 16 -1 (-5025 3825)(-5525 3825);
WIRE 16 -1 (-5025 3875)(-5525 3875);
WIRE 16 -1 (-5025 3925)(-5525 3925);
WIRE 16 -1 (-5025 3975)(-5525 3975);
WIRE 16 -1 (-5025 4025)(-5525 4025);
WIRE 16 -1 (-5025 4075)(-5525 4075);
WIRE 16 -1 (-5025 4175)(-5525 4175);
WIRE 16 -1 (-5025 4225)(-5525 4225);
WIRE 16 -1 (-5025 4325)(-5525 4325);
WIRE 16 -1 (-5025 4375)(-5525 4375);
WIRE 16 -1 (-5025 4425)(-5525 4425);
WIRE 16 -1 (-5025 4475)(-5525 4475);
WIRE 16 -1 (-5025 4525)(-5525 4525);
WIRE 16 -1 (-5025 4575)(-5525 4575);
WIRE 16 -1 (-5025 4625)(-5525 4625);
WIRE 16 -1 (-5025 4675)(-5525 4675);
WIRE 16 -1 (-3325 1425)(-2900 1425);
WIRE 16 -1 (-3325 1475)(-2900 1475);
WIRE 16 -1 (-3325 1575)(-2900 1575);
WIRE 16 -1 (-3325 1925)(-2900 1925);
WIRE 16 -1 (-3325 1975)(-2900 1975);
WIRE 16 -1 (-3325 2025)(-2900 2025);
WIRE 16 -1 (-3325 975)(-2900 975);
WIRE 16 -1 (-3325 1025)(-2900 1025);
WIRE 16 -1 (-3325 1075)(-2900 1075);
WIRE 16 -1 (-3325 1125)(-2900 1125);
WIRE 16 -1 (-3325 1175)(-2900 1175);
WIRE 16 -1 (-3325 1225)(-2900 1225);
WIRE 16 -1 (-3325 1275)(-2900 1275);
WIRE 16 -1 (-3325 1325)(-2900 1325);
WIRE 16 -1 (-3325 1675)(-2900 1675);
WIRE 16 -1 (-3325 1725)(-2900 1725);
WIRE 16 -1 (-3325 1775)(-2900 1775);
WIRE 16 -1 (-3325 1825)(-2900 1825);
WIRE 16 -1 (-3325 825)(-2900 825);
WIRE 16 -1 (-3325 875)(-2900 875);
WIRE 16 -1 (-3325 725)(-2900 725);
WIRE 16 -1 (-3325 775)(-2900 775);
WIRE 16 -1 (-3325 525)(-2050 525);
FORCEPROP 2 LAST SIG_NAME M_G_PAR
J 0
(-2700 535);
DISPLAY 0.617021 (-2700 535);
PAINT ORANGE (-2700 535);
WIRE 16 -1 (-3325 575)(-2050 575);
FORCEPROP 2 LAST SIG_NAME M_G_ALERT_N
J 0
(-2700 585);
DISPLAY 0.617021 (-2700 585);
PAINT ORANGE (-2700 585);
WIRE 16 -1 (-3325 625)(-2050 625);
FORCEPROP 2 LAST SIG_NAME M_G_ACT_N
J 0
(-2700 635);
DISPLAY 0.617021 (-2700 635);
PAINT ORANGE (-2700 635);
WIRE 16 -1 (-3325 2075)(-2900 2075);
WIRE 16 -1 (-3325 2125)(-2900 2125);
WIRE 16 -1 (-3325 2175)(-2900 2175);
WIRE 16 -1 (-3325 2225)(-2900 2225);
WIRE 16 -1 (-3325 2275)(-2900 2275);
WIRE 16 -1 (-3325 2325)(-2900 2325);
WIRE 16 -1 (-3325 2375)(-2900 2375);
WIRE 16 -1 (-3325 2425)(-2900 2425);
WIRE 16 -1 (-3325 2475)(-2900 2475);
WIRE 16 -1 (-3325 2525)(-2900 2525);
WIRE 16 -1 (-3325 2575)(-2900 2575);
WIRE 16 -1 (-3325 2625)(-2900 2625);
WIRE 16 -1 (-3325 2675)(-2900 2675);
WIRE 16 -1 (-3325 2725)(-2900 2725);
WIRE 16 -1 (-3325 2775)(-2900 2775);
WIRE 16 -1 (-3325 3825)(-2900 3825);
WIRE 16 -1 (-3325 3875)(-2900 3875);
WIRE 16 -1 (-3325 3925)(-2900 3925);
WIRE 16 -1 (-3325 3975)(-2900 3975);
WIRE 16 -1 (-3325 4025)(-2900 4025);
WIRE 16 -1 (-3325 4075)(-2900 4075);
WIRE 16 -1 (-3325 2875)(-2900 2875);
WIRE 16 -1 (-3325 2925)(-2900 2925);
WIRE 16 -1 (-3325 2975)(-2900 2975);
WIRE 16 -1 (-3325 3025)(-2900 3025);
WIRE 16 -1 (-3325 3075)(-2900 3075);
WIRE 16 -1 (-3325 3125)(-2900 3125);
WIRE 16 -1 (-3325 3175)(-2900 3175);
WIRE 16 -1 (-3325 3225)(-2900 3225);
WIRE 16 -1 (-3325 3275)(-2900 3275);
WIRE 16 -1 (-3325 3325)(-2900 3325);
WIRE 16 -1 (-3325 3375)(-2900 3375);
WIRE 16 -1 (-3325 3425)(-2900 3425);
WIRE 16 -1 (-3325 3475)(-2900 3475);
WIRE 16 -1 (-3325 3525)(-2900 3525);
WIRE 16 -1 (-3325 3575)(-2900 3575);
WIRE 16 -1 (-3325 3625)(-2900 3625);
WIRE 16 -1 (-3325 3675)(-2900 3675);
WIRE 16 -1 (-3325 3725)(-2900 3725);
WIRE 16 -1 (-3325 4125)(-2900 4125);
WIRE 16 -1 (-3325 4175)(-2900 4175);
WIRE 16 -1 (-3325 4225)(-2900 4225);
WIRE 16 -1 (-3325 4275)(-2900 4275);
WIRE 16 -1 (-3325 4325)(-2900 4325);
WIRE 16 -1 (-3325 4375)(-2900 4375);
WIRE 16 -1 (-3325 4425)(-2900 4425);
WIRE 16 -1 (-3325 4475)(-2900 4475);
WIRE 16 -1 (-3325 4525)(-2900 4525);
WIRE 16 -1 (-3325 4575)(-2900 4575);
WIRE 16 -1 (-3325 4625)(-2900 4625);
WIRE 16 -1 (-3325 4675)(-2900 4675);
FORCENOTE
ROOM=CPU1
(-7925 400) 0;
DISPLAY LEFT (-7925 400);
DISPLAY 1.723404 (-7925 400);
PAINT PURPLE (-7925 400);
FORCENOTE
BOM_COST=PROC_SOCKET
(-7925 275) 0;
DISPLAY LEFT (-7925 275);
DISPLAY 1.723404 (-7925 275);
PAINT PURPLE (-7925 275);
QUIT
